FILE_TYPE = MACRO_DRAWING;
SET COLOR_WIRE YELLOW;
SET COLOR_PROP ORANGE;
SET COLOR_DOT WHITE;
SET COLOR_ARC YELLOW;
SET COLOR_BODY GREEN;
SET COLOR_NOTE PURPLE;
SET PROP_DISPLAY VALUE;
SET PAGE_NUMBER P184;
FORCEADD Q_RES..2
(-1125 2075);
FORCEPROP 1 LAST PART_NUMBER CS21002FB06
J 0
(-1085 1950);
DISPLAY 0.510638 (-1085 1950);
DISPLAY INVISIBLE (-1085 1950);
FORCEPROP 1 LAST WATTAGE 1/16W
J 0
(-1085 2050);
DISPLAY 0.638298 (-1085 2050);
FORCEPROP 1 LAST TOLERANCE 1%
J 0
(-1080 2100);
DISPLAY 0.638298 (-1080 2100);
FORCEPROP 1 LAST VALUE 1K
J 0
(-1080 2150);
DISPLAY 0.638298 (-1080 2150);
FORCEPROP 1 LAST PACK_TYPE 0402LF
J 0
(-1085 1950);
DISPLAY 0.638298 (-1085 1950);
FORCEPROP 1 LAST MATERIAL CHIP
J 0
(-1085 2000);
DISPLAY 0.638298 (-1085 2000);
FORCEPROP 1 LAST $LOCATION R4581
J 0
(-1080 2200);
DISPLAY 0.978723 (-1080 2200);
FORCEPROP 1 LASTPIN (-1125 2175) $PN 1
J 0
(-1120 2137);
DISPLAY 0.787234 (-1120 2137);
PAINT MONO (-1120 2137);
FORCEPROP 1 LASTPIN (-1125 1975) $PN 2
J 0
(-1120 1985);
DISPLAY 0.787234 (-1120 1985);
PAINT MONO (-1120 1985);
FORCEPROP 2 LAST CDS_LIB pure_quanta
J 0
(-1125 2075);
DISPLAY INVISIBLE (-1125 2075);
FORCEPROP 1 LAST PATH I1
J 0
(-1075 2250);
DISPLAY 0.978723 (-1075 2250);
PAINT WHITE (-1075 2250);
DISPLAY INVISIBLE (-1075 2250);
FORCEPROP 0 LAST CDS_LOCATION R4581
J 0
(-1075 2250);
DISPLAY 1.021277 (-1075 2250);
DISPLAY INVISIBLE (-1075 2250);
FORCEPROP 0 LAST $SEC 1
J 0
(-1075 2250);
DISPLAY 0.680851 (-1075 2250);
PAINT MONO (-1075 2250);
DISPLAY INVISIBLE (-1075 2250);
FORCEPROP 0 LAST CDS_SEC 1
J 0
(-1075 2250);
DISPLAY 1.021277 (-1075 2250);
DISPLAY INVISIBLE (-1075 2250);
FORCEADD UNIVERSAL_GND..1
(-950 4175);
FORCEPROP 3 LASTPIN (-950 4225) SIG_NAME GND\g
J 0
(-940 4235);
DISPLAY 0.659574 (-940 4235);
PAINT MONO (-940 4235);
DISPLAY INVISIBLE (-940 4235);
FORCEPROP 1 LAST HDL_POWER GND
J 1
(-925 4100);
DISPLAY 0.872340 (-925 4100);
PAINT GREEN (-925 4100);
DISPLAY INVISIBLE (-925 4100);
FORCEPROP 2 LAST CDS_LIB logical_power
J 0
(-950 4175);
PAINT MONO (-950 4175);
DISPLAY INVISIBLE (-950 4175);
FORCEPROP 1 LAST PATH I10
J 0
(-875 4175);
DISPLAY 0.872340 (-875 4175);
PAINT AQUA (-875 4175);
DISPLAY INVISIBLE (-875 4175);
FORCEADD Q_RES..2
(-950 4400);
FORCEPROP 1 LAST PART_NUMBER CS21002FB06
J 0
(-910 4275);
DISPLAY 0.510638 (-910 4275);
DISPLAY INVISIBLE (-910 4275);
FORCEPROP 1 LAST PACK_TYPE 0402LF
J 0
(-910 4275);
DISPLAY 0.638298 (-910 4275);
FORCEPROP 1 LAST TOLERANCE 1%
J 0
(-905 4425);
DISPLAY 0.638298 (-905 4425);
FORCEPROP 1 LAST WATTAGE 1/16W
J 0
(-910 4375);
DISPLAY 0.638298 (-910 4375);
FORCEPROP 1 LAST VALUE 1K
J 0
(-905 4475);
DISPLAY 0.638298 (-905 4475);
FORCEPROP 1 LAST MATERIAL CHIP
J 0
(-910 4325);
DISPLAY 0.638298 (-910 4325);
FORCEPROP 1 LAST $LOCATION R2977
J 0
(-905 4525);
DISPLAY 0.978723 (-905 4525);
FORCEPROP 1 LASTPIN (-950 4500) $PN 1
J 0
(-945 4462);
DISPLAY 0.787234 (-945 4462);
PAINT MONO (-945 4462);
FORCEPROP 1 LASTPIN (-950 4300) $PN 2
J 0
(-945 4310);
DISPLAY 0.787234 (-945 4310);
PAINT MONO (-945 4310);
FORCEPROP 2 LAST CDS_LIB pure_quanta
J 0
(-950 4400);
DISPLAY INVISIBLE (-950 4400);
FORCEPROP 1 LAST PATH I11
J 0
(-900 4575);
DISPLAY 0.978723 (-900 4575);
PAINT WHITE (-900 4575);
DISPLAY INVISIBLE (-900 4575);
FORCEPROP 0 LAST CDS_LOCATION R2977
J 0
(-900 4575);
DISPLAY 1.021277 (-900 4575);
DISPLAY INVISIBLE (-900 4575);
FORCEPROP 0 LAST $SEC 1
J 0
(-900 4575);
DISPLAY 0.680851 (-900 4575);
PAINT MONO (-900 4575);
DISPLAY INVISIBLE (-900 4575);
FORCEPROP 0 LAST CDS_SEC 1
J 0
(-900 4575);
DISPLAY 1.021277 (-900 4575);
DISPLAY INVISIBLE (-900 4575);
FORCEADD Q_RES..2
(-1225 5225);
FORCEPROP 1 LAST PART_NUMBER CS31002FB08
J 0
(-1185 5100);
DISPLAY 0.510638 (-1185 5100);
DISPLAY INVISIBLE (-1185 5100);
FORCEPROP 1 LAST PACK_TYPE 0402LF
J 0
(-1185 5100);
DISPLAY 0.638298 (-1185 5100);
FORCEPROP 1 LAST TOLERANCE 1%
J 0
(-1180 5250);
DISPLAY 0.638298 (-1180 5250);
FORCEPROP 1 LAST MATERIAL EMPTY
J 0
(-1185 5150);
DISPLAY 0.638298 (-1185 5150);
PAINT RED (-1185 5150);
FORCEPROP 1 LAST WATTAGE 1/16W
J 0
(-1185 5200);
DISPLAY 0.638298 (-1185 5200);
FORCEPROP 1 LAST VALUE 10K
J 0
(-1180 5300);
DISPLAY 0.638298 (-1180 5300);
FORCEPROP 1 LAST $LOCATION R2234
J 0
(-1180 5350);
DISPLAY 0.978723 (-1180 5350);
FORCEPROP 1 LASTPIN (-1225 5325) $PN 1
J 0
(-1220 5287);
DISPLAY 0.787234 (-1220 5287);
PAINT MONO (-1220 5287);
FORCEPROP 1 LASTPIN (-1225 5125) $PN 2
J 0
(-1220 5135);
DISPLAY 0.787234 (-1220 5135);
PAINT MONO (-1220 5135);
FORCEPROP 2 LAST CDS_LIB pure_quanta
J 0
(-1225 5225);
DISPLAY INVISIBLE (-1225 5225);
FORCEPROP 1 LAST PATH I12
J 0
(-1175 5400);
DISPLAY 0.978723 (-1175 5400);
PAINT WHITE (-1175 5400);
DISPLAY INVISIBLE (-1175 5400);
FORCEPROP 0 LAST CDS_LOCATION R2234
J 0
(-1175 5400);
DISPLAY 1.021277 (-1175 5400);
DISPLAY INVISIBLE (-1175 5400);
FORCEPROP 0 LAST $SEC 1
J 0
(-1175 5400);
DISPLAY 0.680851 (-1175 5400);
PAINT MONO (-1175 5400);
DISPLAY INVISIBLE (-1175 5400);
FORCEPROP 0 LAST CDS_SEC 1
J 0
(-1175 5400);
DISPLAY 1.021277 (-1175 5400);
DISPLAY INVISIBLE (-1175 5400);
FORCEADD Q_RES..2
(-950 5225);
FORCEPROP 1 LAST PART_NUMBER CS31002FB08
J 0
(-910 5100);
DISPLAY 0.510638 (-910 5100);
DISPLAY INVISIBLE (-910 5100);
FORCEPROP 1 LAST TOLERANCE 1%
J 0
(-905 5250);
DISPLAY 0.638298 (-905 5250);
FORCEPROP 1 LAST WATTAGE 1/16W
J 0
(-910 5200);
DISPLAY 0.638298 (-910 5200);
FORCEPROP 1 LAST MATERIAL EMPTY
J 0
(-910 5150);
DISPLAY 0.638298 (-910 5150);
PAINT RED (-910 5150);
FORCEPROP 1 LAST VALUE 10K
J 0
(-905 5300);
DISPLAY 0.638298 (-905 5300);
FORCEPROP 1 LAST PACK_TYPE 0402LF
J 0
(-910 5100);
DISPLAY 0.638298 (-910 5100);
FORCEPROP 1 LAST $LOCATION R2976
J 0
(-905 5350);
DISPLAY 0.978723 (-905 5350);
FORCEPROP 1 LASTPIN (-950 5325) $PN 1
J 0
(-945 5287);
DISPLAY 0.787234 (-945 5287);
PAINT MONO (-945 5287);
FORCEPROP 1 LASTPIN (-950 5125) $PN 2
J 0
(-945 5135);
DISPLAY 0.787234 (-945 5135);
PAINT MONO (-945 5135);
FORCEPROP 2 LAST CDS_LIB pure_quanta
J 0
(-950 5225);
DISPLAY INVISIBLE (-950 5225);
FORCEPROP 1 LAST PATH I13
J 0
(-900 5400);
DISPLAY 0.978723 (-900 5400);
PAINT WHITE (-900 5400);
DISPLAY INVISIBLE (-900 5400);
FORCEPROP 0 LAST CDS_LOCATION R2976
J 0
(-900 5400);
DISPLAY 1.021277 (-900 5400);
DISPLAY INVISIBLE (-900 5400);
FORCEPROP 0 LAST $SEC 1
J 0
(-900 5400);
DISPLAY 0.680851 (-900 5400);
PAINT MONO (-900 5400);
DISPLAY INVISIBLE (-900 5400);
FORCEPROP 0 LAST CDS_SEC 1
J 0
(-900 5400);
DISPLAY 1.021277 (-900 5400);
DISPLAY INVISIBLE (-900 5400);
FORCEADD UNIVERSAL_POWER..1
(-1225 5600);
FORCEPROP 3 LASTPIN (-1225 5550) SIG_NAME P1V05_PCH_AUX\g
J 0
(-1215 5560);
DISPLAY 0.659574 (-1215 5560);
PAINT MONO (-1215 5560);
DISPLAY INVISIBLE (-1215 5560);
FORCEPROP 1 LAST HDL_POWER P1V05_PCH_AUX
J 1
(-1225 5650);
DISPLAY 0.872340 (-1225 5650);
PAINT GREEN (-1225 5650);
FORCEPROP 2 LAST CDS_LIB logical_power
J 0
(-1225 5600);
PAINT MONO (-1225 5600);
DISPLAY INVISIBLE (-1225 5600);
FORCEPROP 1 LAST PATH I14
J 0
(-1175 5625);
DISPLAY 0.872340 (-1175 5625);
PAINT AQUA (-1175 5625);
DISPLAY INVISIBLE (-1175 5625);
FORCEADD UNIVERSAL_GND..1
(-575 1850);
FORCEPROP 3 LASTPIN (-575 1900) SIG_NAME GND\g
J 0
(-565 1910);
DISPLAY 0.659574 (-565 1910);
PAINT MONO (-565 1910);
DISPLAY INVISIBLE (-565 1910);
FORCEPROP 1 LAST HDL_POWER GND
J 1
(-550 1775);
DISPLAY 0.872340 (-550 1775);
PAINT GREEN (-550 1775);
DISPLAY INVISIBLE (-550 1775);
FORCEPROP 2 LAST CDS_LIB logical_power
J 0
(-575 1850);
PAINT MONO (-575 1850);
DISPLAY INVISIBLE (-575 1850);
FORCEPROP 1 LAST PATH I15
J 0
(-500 1850);
DISPLAY 0.872340 (-500 1850);
PAINT AQUA (-500 1850);
DISPLAY INVISIBLE (-500 1850);
FORCEADD Q_RES..2
(-575 2075);
FORCEPROP 1 LAST PART_NUMBER CS21002FB06
J 0
(-535 1950);
DISPLAY 0.510638 (-535 1950);
DISPLAY INVISIBLE (-535 1950);
FORCEPROP 1 LAST TOLERANCE 1%
J 0
(-530 2100);
DISPLAY 0.638298 (-530 2100);
FORCEPROP 1 LAST PACK_TYPE 0402LF
J 0
(-535 1950);
DISPLAY 0.638298 (-535 1950);
FORCEPROP 1 LAST MATERIAL CHIP
J 0
(-535 2000);
DISPLAY 0.638298 (-535 2000);
FORCEPROP 1 LAST WATTAGE 1/16W
J 0
(-535 2050);
DISPLAY 0.638298 (-535 2050);
FORCEPROP 1 LAST VALUE 1K
J 0
(-530 2150);
DISPLAY 0.638298 (-530 2150);
FORCEPROP 1 LAST $LOCATION R4598
J 0
(-530 2200);
DISPLAY 0.978723 (-530 2200);
FORCEPROP 1 LASTPIN (-575 2175) $PN 1
J 0
(-570 2137);
DISPLAY 0.787234 (-570 2137);
PAINT MONO (-570 2137);
FORCEPROP 1 LASTPIN (-575 1975) $PN 2
J 0
(-570 1985);
DISPLAY 0.787234 (-570 1985);
PAINT MONO (-570 1985);
FORCEPROP 2 LAST CDS_LIB pure_quanta
J 0
(-575 2075);
DISPLAY INVISIBLE (-575 2075);
FORCEPROP 1 LAST PATH I16
J 0
(-525 2250);
DISPLAY 0.978723 (-525 2250);
PAINT WHITE (-525 2250);
DISPLAY INVISIBLE (-525 2250);
FORCEPROP 0 LAST CDS_LOCATION R4598
J 0
(-525 2250);
DISPLAY 1.021277 (-525 2250);
DISPLAY INVISIBLE (-525 2250);
FORCEPROP 0 LAST $SEC 1
J 0
(-525 2250);
DISPLAY 0.680851 (-525 2250);
PAINT MONO (-525 2250);
DISPLAY INVISIBLE (-525 2250);
FORCEPROP 0 LAST CDS_SEC 1
J 0
(-525 2250);
DISPLAY 1.021277 (-525 2250);
DISPLAY INVISIBLE (-525 2250);
FORCEADD UNIVERSAL_GND..1
(-300 1850);
FORCEPROP 3 LASTPIN (-300 1900) SIG_NAME GND\g
J 0
(-290 1910);
DISPLAY 0.659574 (-290 1910);
PAINT MONO (-290 1910);
DISPLAY INVISIBLE (-290 1910);
FORCEPROP 1 LAST HDL_POWER GND
J 1
(-275 1775);
DISPLAY 0.872340 (-275 1775);
PAINT GREEN (-275 1775);
DISPLAY INVISIBLE (-275 1775);
FORCEPROP 2 LAST CDS_LIB logical_power
J 0
(-300 1850);
PAINT MONO (-300 1850);
DISPLAY INVISIBLE (-300 1850);
FORCEPROP 1 LAST PATH I17
J 0
(-225 1850);
DISPLAY 0.872340 (-225 1850);
PAINT AQUA (-225 1850);
DISPLAY INVISIBLE (-225 1850);
FORCEADD Q_RES..2
(-300 2075);
FORCEPROP 1 LAST PART_NUMBER CS21002FB06
J 0
(-260 1950);
DISPLAY 0.510638 (-260 1950);
DISPLAY INVISIBLE (-260 1950);
FORCEPROP 1 LAST VALUE 1K
J 0
(-255 2150);
DISPLAY 0.638298 (-255 2150);
FORCEPROP 1 LAST TOLERANCE 1%
J 0
(-255 2100);
DISPLAY 0.638298 (-255 2100);
FORCEPROP 1 LAST PACK_TYPE 0402LF
J 0
(-260 1950);
DISPLAY 0.638298 (-260 1950);
FORCEPROP 1 LAST WATTAGE 1/16W
J 0
(-260 2050);
DISPLAY 0.638298 (-260 2050);
FORCEPROP 1 LAST MATERIAL CHIP
J 0
(-260 2000);
DISPLAY 0.638298 (-260 2000);
FORCEPROP 1 LAST $LOCATION R4583
J 0
(-255 2200);
DISPLAY 0.978723 (-255 2200);
FORCEPROP 1 LASTPIN (-300 2175) $PN 1
J 0
(-295 2137);
DISPLAY 0.787234 (-295 2137);
PAINT MONO (-295 2137);
FORCEPROP 1 LASTPIN (-300 1975) $PN 2
J 0
(-295 1985);
DISPLAY 0.787234 (-295 1985);
PAINT MONO (-295 1985);
FORCEPROP 2 LAST CDS_LIB pure_quanta
J 0
(-300 2075);
DISPLAY INVISIBLE (-300 2075);
FORCEPROP 1 LAST PATH I18
J 0
(-250 2250);
DISPLAY 0.978723 (-250 2250);
PAINT WHITE (-250 2250);
DISPLAY INVISIBLE (-250 2250);
FORCEPROP 0 LAST CDS_LOCATION R4583
J 0
(-250 2250);
DISPLAY 1.021277 (-250 2250);
DISPLAY INVISIBLE (-250 2250);
FORCEPROP 0 LAST $SEC 1
J 0
(-250 2250);
DISPLAY 0.680851 (-250 2250);
PAINT MONO (-250 2250);
DISPLAY INVISIBLE (-250 2250);
FORCEPROP 0 LAST CDS_SEC 1
J 0
(-250 2250);
DISPLAY 1.021277 (-250 2250);
DISPLAY INVISIBLE (-250 2250);
FORCEADD UNIVERSAL_GND..1
(-25 1850);
FORCEPROP 3 LASTPIN (-25 1900) SIG_NAME GND\g
J 0
(-15 1910);
DISPLAY 0.659574 (-15 1910);
PAINT MONO (-15 1910);
DISPLAY INVISIBLE (-15 1910);
FORCEPROP 1 LAST HDL_POWER GND
J 1
(0 1775);
DISPLAY 0.872340 (0 1775);
PAINT GREEN (0 1775);
DISPLAY INVISIBLE (0 1775);
FORCEPROP 2 LAST CDS_LIB logical_power
J 0
(-25 1850);
PAINT MONO (-25 1850);
DISPLAY INVISIBLE (-25 1850);
FORCEPROP 1 LAST PATH I19
J 0
(50 1850);
DISPLAY 0.872340 (50 1850);
PAINT AQUA (50 1850);
DISPLAY INVISIBLE (50 1850);
FORCEADD UNIVERSAL_GND..1
(-1125 1850);
FORCEPROP 3 LASTPIN (-1125 1900) SIG_NAME GND\g
J 0
(-1115 1910);
DISPLAY 0.659574 (-1115 1910);
PAINT MONO (-1115 1910);
DISPLAY INVISIBLE (-1115 1910);
FORCEPROP 1 LAST HDL_POWER GND
J 1
(-1100 1775);
DISPLAY 0.872340 (-1100 1775);
PAINT GREEN (-1100 1775);
DISPLAY INVISIBLE (-1100 1775);
FORCEPROP 2 LAST CDS_LIB logical_power
J 0
(-1125 1850);
PAINT MONO (-1125 1850);
DISPLAY INVISIBLE (-1125 1850);
FORCEPROP 1 LAST PATH I2
J 0
(-1050 1850);
DISPLAY 0.872340 (-1050 1850);
PAINT AQUA (-1050 1850);
DISPLAY INVISIBLE (-1050 1850);
FORCEADD Q_RES..2
(-25 2075);
FORCEPROP 1 LAST PART_NUMBER CS21002FB06
J 0
(15 1950);
DISPLAY 0.510638 (15 1950);
DISPLAY INVISIBLE (15 1950);
FORCEPROP 1 LAST VALUE 1K
J 0
(20 2150);
DISPLAY 0.638298 (20 2150);
FORCEPROP 1 LAST TOLERANCE 1%
J 0
(20 2100);
DISPLAY 0.638298 (20 2100);
FORCEPROP 1 LAST MATERIAL CHIP
J 0
(15 2000);
DISPLAY 0.638298 (15 2000);
FORCEPROP 1 LAST WATTAGE 1/16W
J 0
(15 2050);
DISPLAY 0.638298 (15 2050);
FORCEPROP 1 LAST PACK_TYPE 0402LF
J 0
(15 1900);
DISPLAY 0.638298 (15 1900);
FORCEPROP 1 LAST $LOCATION R4585
J 0
(20 2200);
DISPLAY 0.978723 (20 2200);
FORCEPROP 1 LASTPIN (-25 2175) $PN 1
J 0
(-20 2137);
DISPLAY 0.787234 (-20 2137);
PAINT MONO (-20 2137);
FORCEPROP 1 LASTPIN (-25 1975) $PN 2
J 0
(-20 1985);
DISPLAY 0.787234 (-20 1985);
PAINT MONO (-20 1985);
FORCEPROP 2 LAST CDS_LIB pure_quanta
J 0
(-25 2075);
DISPLAY INVISIBLE (-25 2075);
FORCEPROP 1 LAST PATH I20
J 0
(25 2250);
DISPLAY 0.978723 (25 2250);
PAINT WHITE (25 2250);
DISPLAY INVISIBLE (25 2250);
FORCEPROP 0 LAST CDS_LOCATION R4585
J 0
(25 2250);
DISPLAY 1.021277 (25 2250);
DISPLAY INVISIBLE (25 2250);
FORCEPROP 0 LAST $SEC 1
J 0
(25 2250);
DISPLAY 0.680851 (25 2250);
PAINT MONO (25 2250);
DISPLAY INVISIBLE (25 2250);
FORCEPROP 0 LAST CDS_SEC 1
J 0
(25 2250);
DISPLAY 1.021277 (25 2250);
DISPLAY INVISIBLE (25 2250);
FORCEADD OFFPAGE..2
(1100 2325);
FORCEPROP 2 LAST $XR0 216 
J 0
(1289 2325);
DISPLAY 0.638298 (1289 2325);
PAINT MONO (1289 2325);
FORCEPROP 2 LAST CDS_LIB standard
J 0
(1100 2325);
PAINT MONO (1100 2325);
DISPLAY INVISIBLE (1100 2325);
FORCEPROP 1 LAST OFFPAGE TRUE
J 0
(1425 2200);
DISPLAY 0.872340 (1425 2200);
DISPLAY INVISIBLE (1425 2200);
FORCEPROP 1 LAST COMMENT_BODY TRUE
J 0
(1055 2230);
DISPLAY 0.872340 (1055 2230);
PAINT GREEN (1055 2230);
DISPLAY INVISIBLE (1055 2230);
FORCEPROP 2 LAST PATH I21
J 0
(1300 2375);
DISPLAY 1.021277 (1300 2375);
DISPLAY INVISIBLE (1300 2375);
FORCEADD Q_RES..2
(-575 2900);
FORCEPROP 1 LAST PART_NUMBER CS31002FB08
J 0
(-535 2775);
DISPLAY 0.510638 (-535 2775);
DISPLAY INVISIBLE (-535 2775);
FORCEPROP 1 LAST WATTAGE 1/16W
J 0
(-535 2875);
DISPLAY 0.638298 (-535 2875);
FORCEPROP 1 LAST VALUE 10K
J 0
(-530 2975);
DISPLAY 0.638298 (-530 2975);
FORCEPROP 1 LAST TOLERANCE 1%
J 0
(-530 2925);
DISPLAY 0.638298 (-530 2925);
FORCEPROP 1 LAST PACK_TYPE 0402LF
J 0
(-535 2775);
DISPLAY 0.638298 (-535 2775);
FORCEPROP 1 LAST MATERIAL EMPTY
J 0
(-535 2825);
DISPLAY 0.638298 (-535 2825);
PAINT RED (-535 2825);
FORCEPROP 1 LAST $LOCATION R4597
J 0
(-530 3025);
DISPLAY 0.978723 (-530 3025);
FORCEPROP 1 LASTPIN (-575 3000) $PN 1
J 0
(-570 2962);
DISPLAY 0.787234 (-570 2962);
PAINT MONO (-570 2962);
FORCEPROP 1 LASTPIN (-575 2800) $PN 2
J 0
(-570 2810);
DISPLAY 0.787234 (-570 2810);
PAINT MONO (-570 2810);
FORCEPROP 2 LAST CDS_LIB pure_quanta
J 0
(-575 2900);
DISPLAY INVISIBLE (-575 2900);
FORCEPROP 1 LAST PATH I22
J 0
(-525 3075);
DISPLAY 0.978723 (-525 3075);
PAINT WHITE (-525 3075);
DISPLAY INVISIBLE (-525 3075);
FORCEPROP 0 LAST CDS_LOCATION R4597
J 0
(-525 3075);
DISPLAY 1.021277 (-525 3075);
DISPLAY INVISIBLE (-525 3075);
FORCEPROP 0 LAST $SEC 1
J 0
(-525 3075);
DISPLAY 0.680851 (-525 3075);
PAINT MONO (-525 3075);
DISPLAY INVISIBLE (-525 3075);
FORCEPROP 0 LAST CDS_SEC 1
J 0
(-525 3075);
DISPLAY 1.021277 (-525 3075);
DISPLAY INVISIBLE (-525 3075);
FORCEADD Q_RES..2
(-300 2900);
FORCEPROP 1 LAST PART_NUMBER CS31002FB08
J 0
(-260 2775);
DISPLAY 0.510638 (-260 2775);
DISPLAY INVISIBLE (-260 2775);
FORCEPROP 1 LAST TOLERANCE 1%
J 0
(-255 2925);
DISPLAY 0.638298 (-255 2925);
FORCEPROP 1 LAST WATTAGE 1/16W
J 0
(-260 2875);
DISPLAY 0.638298 (-260 2875);
FORCEPROP 1 LAST PACK_TYPE 0402LF
J 0
(-260 2775);
DISPLAY 0.638298 (-260 2775);
FORCEPROP 1 LAST VALUE 10K
J 0
(-255 2975);
DISPLAY 0.638298 (-255 2975);
FORCEPROP 1 LAST MATERIAL EMPTY
J 0
(-260 2825);
DISPLAY 0.638298 (-260 2825);
PAINT RED (-260 2825);
FORCEPROP 1 LAST $LOCATION R4582
J 0
(-255 3025);
DISPLAY 0.978723 (-255 3025);
FORCEPROP 1 LASTPIN (-300 3000) $PN 1
J 0
(-295 2962);
DISPLAY 0.787234 (-295 2962);
PAINT MONO (-295 2962);
FORCEPROP 1 LASTPIN (-300 2800) $PN 2
J 0
(-295 2810);
DISPLAY 0.787234 (-295 2810);
PAINT MONO (-295 2810);
FORCEPROP 2 LAST CDS_LIB pure_quanta
J 0
(-300 2900);
DISPLAY INVISIBLE (-300 2900);
FORCEPROP 1 LAST PATH I23
J 0
(-250 3075);
DISPLAY 0.978723 (-250 3075);
PAINT WHITE (-250 3075);
DISPLAY INVISIBLE (-250 3075);
FORCEPROP 0 LAST CDS_LOCATION R4582
J 0
(-250 3075);
DISPLAY 1.021277 (-250 3075);
DISPLAY INVISIBLE (-250 3075);
FORCEPROP 0 LAST $SEC 1
J 0
(-250 3075);
DISPLAY 0.680851 (-250 3075);
PAINT MONO (-250 3075);
DISPLAY INVISIBLE (-250 3075);
FORCEPROP 0 LAST CDS_SEC 1
J 0
(-250 3075);
DISPLAY 1.021277 (-250 3075);
DISPLAY INVISIBLE (-250 3075);
FORCEADD Q_RES..2
(-25 2900);
FORCEPROP 1 LAST PART_NUMBER CS31002FB08
J 0
(15 2775);
DISPLAY 0.510638 (15 2775);
DISPLAY INVISIBLE (15 2775);
FORCEPROP 1 LAST TOLERANCE 1%
J 0
(20 2925);
DISPLAY 0.638298 (20 2925);
FORCEPROP 1 LAST WATTAGE 1/16W
J 0
(15 2875);
DISPLAY 0.638298 (15 2875);
FORCEPROP 1 LAST MATERIAL EMPTY
J 0
(15 2825);
DISPLAY 0.638298 (15 2825);
PAINT RED (15 2825);
FORCEPROP 1 LAST VALUE 10K
J 0
(20 2975);
DISPLAY 0.638298 (20 2975);
FORCEPROP 1 LAST PACK_TYPE 0402LF
J 0
(15 2725);
DISPLAY 0.638298 (15 2725);
FORCEPROP 1 LAST $LOCATION R4584
J 0
(20 3025);
DISPLAY 0.978723 (20 3025);
FORCEPROP 1 LASTPIN (-25 3000) $PN 1
J 0
(-20 2962);
DISPLAY 0.787234 (-20 2962);
PAINT MONO (-20 2962);
FORCEPROP 1 LASTPIN (-25 2800) $PN 2
J 0
(-20 2810);
DISPLAY 0.787234 (-20 2810);
PAINT MONO (-20 2810);
FORCEPROP 2 LAST CDS_LIB pure_quanta
J 0
(-25 2900);
DISPLAY INVISIBLE (-25 2900);
FORCEPROP 1 LAST PATH I24
J 0
(25 3075);
DISPLAY 0.978723 (25 3075);
PAINT WHITE (25 3075);
DISPLAY INVISIBLE (25 3075);
FORCEPROP 0 LAST CDS_LOCATION R4584
J 0
(25 3075);
DISPLAY 1.021277 (25 3075);
DISPLAY INVISIBLE (25 3075);
FORCEPROP 0 LAST $SEC 1
J 0
(25 3075);
DISPLAY 0.680851 (25 3075);
PAINT MONO (25 3075);
DISPLAY INVISIBLE (25 3075);
FORCEPROP 0 LAST CDS_SEC 1
J 0
(25 3075);
DISPLAY 1.021277 (25 3075);
DISPLAY INVISIBLE (25 3075);
FORCEADD UNIVERSAL_GND..1
(-675 4175);
FORCEPROP 3 LASTPIN (-675 4225) SIG_NAME GND\g
J 0
(-665 4235);
DISPLAY 0.659574 (-665 4235);
PAINT MONO (-665 4235);
DISPLAY INVISIBLE (-665 4235);
FORCEPROP 1 LAST HDL_POWER GND
J 1
(-650 4100);
DISPLAY 0.872340 (-650 4100);
PAINT GREEN (-650 4100);
DISPLAY INVISIBLE (-650 4100);
FORCEPROP 2 LAST CDS_LIB logical_power
J 0
(-675 4175);
PAINT MONO (-675 4175);
DISPLAY INVISIBLE (-675 4175);
FORCEPROP 1 LAST PATH I25
J 0
(-600 4175);
DISPLAY 0.872340 (-600 4175);
PAINT AQUA (-600 4175);
DISPLAY INVISIBLE (-600 4175);
FORCEADD Q_RES..2
(-675 4400);
FORCEPROP 1 LAST PART_NUMBER CS21002FB06
J 0
(-635 4275);
DISPLAY 0.510638 (-635 4275);
DISPLAY INVISIBLE (-635 4275);
FORCEPROP 1 LAST WATTAGE 1/16W
J 0
(-635 4375);
DISPLAY 0.638298 (-635 4375);
FORCEPROP 1 LAST MATERIAL CHIP
J 0
(-635 4325);
DISPLAY 0.638298 (-635 4325);
FORCEPROP 1 LAST VALUE 1K
J 0
(-630 4475);
DISPLAY 0.638298 (-630 4475);
FORCEPROP 1 LAST TOLERANCE 1%
J 0
(-630 4425);
DISPLAY 0.638298 (-630 4425);
FORCEPROP 1 LAST PACK_TYPE 0402LF
J 0
(-635 4275);
DISPLAY 0.638298 (-635 4275);
FORCEPROP 1 LAST $LOCATION R2980
J 0
(-630 4525);
DISPLAY 0.978723 (-630 4525);
FORCEPROP 1 LASTPIN (-675 4500) $PN 1
J 0
(-670 4462);
DISPLAY 0.787234 (-670 4462);
PAINT MONO (-670 4462);
FORCEPROP 1 LASTPIN (-675 4300) $PN 2
J 0
(-670 4310);
DISPLAY 0.787234 (-670 4310);
PAINT MONO (-670 4310);
FORCEPROP 2 LAST CDS_LIB pure_quanta
J 0
(-675 4400);
DISPLAY INVISIBLE (-675 4400);
FORCEPROP 1 LAST PATH I26
J 0
(-625 4575);
DISPLAY 0.978723 (-625 4575);
PAINT WHITE (-625 4575);
DISPLAY INVISIBLE (-625 4575);
FORCEPROP 0 LAST CDS_LOCATION R2980
J 0
(-625 4575);
DISPLAY 1.021277 (-625 4575);
DISPLAY INVISIBLE (-625 4575);
FORCEPROP 0 LAST $SEC 1
J 0
(-625 4575);
DISPLAY 0.680851 (-625 4575);
PAINT MONO (-625 4575);
DISPLAY INVISIBLE (-625 4575);
FORCEPROP 0 LAST CDS_SEC 1
J 0
(-625 4575);
DISPLAY 1.021277 (-625 4575);
DISPLAY INVISIBLE (-625 4575);
FORCEADD UNIVERSAL_GND..1
(-400 4175);
FORCEPROP 3 LASTPIN (-400 4225) SIG_NAME GND\g
J 0
(-390 4235);
DISPLAY 0.659574 (-390 4235);
PAINT MONO (-390 4235);
DISPLAY INVISIBLE (-390 4235);
FORCEPROP 1 LAST HDL_POWER GND
J 1
(-375 4100);
DISPLAY 0.872340 (-375 4100);
PAINT GREEN (-375 4100);
DISPLAY INVISIBLE (-375 4100);
FORCEPROP 2 LAST CDS_LIB logical_power
J 0
(-400 4175);
PAINT MONO (-400 4175);
DISPLAY INVISIBLE (-400 4175);
FORCEPROP 1 LAST PATH I27
J 0
(-325 4175);
DISPLAY 0.872340 (-325 4175);
PAINT AQUA (-325 4175);
DISPLAY INVISIBLE (-325 4175);
FORCEADD Q_RES..2
(-400 4400);
FORCEPROP 1 LAST PART_NUMBER CS21002FB06
J 0
(-360 4275);
DISPLAY 0.510638 (-360 4275);
DISPLAY INVISIBLE (-360 4275);
FORCEPROP 1 LAST WATTAGE 1/16W
J 0
(-360 4375);
DISPLAY 0.638298 (-360 4375);
FORCEPROP 1 LAST MATERIAL CHIP
J 0
(-360 4325);
DISPLAY 0.638298 (-360 4325);
FORCEPROP 1 LAST PACK_TYPE 0402LF
J 0
(-360 4275);
DISPLAY 0.638298 (-360 4275);
FORCEPROP 1 LAST VALUE 1K
J 0
(-355 4475);
DISPLAY 0.638298 (-355 4475);
FORCEPROP 1 LAST TOLERANCE 1%
J 0
(-355 4425);
DISPLAY 0.638298 (-355 4425);
FORCEPROP 1 LAST $LOCATION R2241
J 0
(-355 4525);
DISPLAY 0.978723 (-355 4525);
FORCEPROP 1 LASTPIN (-400 4500) $PN 1
J 0
(-395 4462);
DISPLAY 0.787234 (-395 4462);
PAINT MONO (-395 4462);
FORCEPROP 1 LASTPIN (-400 4300) $PN 2
J 0
(-395 4310);
DISPLAY 0.787234 (-395 4310);
PAINT MONO (-395 4310);
FORCEPROP 2 LAST CDS_LIB pure_quanta
J 0
(-400 4400);
DISPLAY INVISIBLE (-400 4400);
FORCEPROP 1 LAST PATH I28
J 0
(-350 4575);
DISPLAY 0.978723 (-350 4575);
PAINT WHITE (-350 4575);
DISPLAY INVISIBLE (-350 4575);
FORCEPROP 0 LAST CDS_LOCATION R2241
J 0
(-350 4575);
DISPLAY 1.021277 (-350 4575);
DISPLAY INVISIBLE (-350 4575);
FORCEPROP 0 LAST $SEC 1
J 0
(-350 4575);
DISPLAY 0.680851 (-350 4575);
PAINT MONO (-350 4575);
DISPLAY INVISIBLE (-350 4575);
FORCEPROP 0 LAST CDS_SEC 1
J 0
(-350 4575);
DISPLAY 1.021277 (-350 4575);
DISPLAY INVISIBLE (-350 4575);
FORCEADD UNIVERSAL_GND..1
(-125 4175);
FORCEPROP 3 LASTPIN (-125 4225) SIG_NAME GND\g
J 0
(-115 4235);
DISPLAY 0.659574 (-115 4235);
PAINT MONO (-115 4235);
DISPLAY INVISIBLE (-115 4235);
FORCEPROP 1 LAST HDL_POWER GND
J 1
(-100 4100);
DISPLAY 0.872340 (-100 4100);
PAINT GREEN (-100 4100);
DISPLAY INVISIBLE (-100 4100);
FORCEPROP 2 LAST CDS_LIB logical_power
J 0
(-125 4175);
PAINT MONO (-125 4175);
DISPLAY INVISIBLE (-125 4175);
FORCEPROP 1 LAST PATH I29
J 0
(-50 4175);
DISPLAY 0.872340 (-50 4175);
PAINT AQUA (-50 4175);
DISPLAY INVISIBLE (-50 4175);
FORCEADD UNIVERSAL_GND..1
(-850 1850);
FORCEPROP 3 LASTPIN (-850 1900) SIG_NAME GND\g
J 0
(-840 1910);
DISPLAY 0.659574 (-840 1910);
PAINT MONO (-840 1910);
DISPLAY INVISIBLE (-840 1910);
FORCEPROP 1 LAST HDL_POWER GND
J 1
(-825 1775);
DISPLAY 0.872340 (-825 1775);
PAINT GREEN (-825 1775);
DISPLAY INVISIBLE (-825 1775);
FORCEPROP 2 LAST CDS_LIB logical_power
J 0
(-850 1850);
PAINT MONO (-850 1850);
DISPLAY INVISIBLE (-850 1850);
FORCEPROP 1 LAST PATH I3
J 0
(-775 1850);
DISPLAY 0.872340 (-775 1850);
PAINT AQUA (-775 1850);
DISPLAY INVISIBLE (-775 1850);
FORCEADD Q_RES..2
(-125 4400);
FORCEPROP 1 LAST PART_NUMBER CS21002FB06
J 0
(-85 4275);
DISPLAY 0.510638 (-85 4275);
DISPLAY INVISIBLE (-85 4275);
FORCEPROP 1 LAST WATTAGE 1/16W
J 0
(-85 4375);
DISPLAY 0.638298 (-85 4375);
FORCEPROP 1 LAST MATERIAL CHIP
J 0
(-85 4325);
DISPLAY 0.638298 (-85 4325);
FORCEPROP 1 LAST VALUE 1K
J 0
(-80 4475);
DISPLAY 0.638298 (-80 4475);
FORCEPROP 1 LAST TOLERANCE 1%
J 0
(-80 4425);
DISPLAY 0.638298 (-80 4425);
FORCEPROP 1 LAST PACK_TYPE 0402LF
J 0
(-85 4225);
DISPLAY 0.638298 (-85 4225);
FORCEPROP 1 LAST $LOCATION R2243
J 0
(-80 4525);
DISPLAY 0.978723 (-80 4525);
FORCEPROP 1 LASTPIN (-125 4500) $PN 1
J 0
(-120 4462);
DISPLAY 0.787234 (-120 4462);
PAINT MONO (-120 4462);
FORCEPROP 1 LASTPIN (-125 4300) $PN 2
J 0
(-120 4310);
DISPLAY 0.787234 (-120 4310);
PAINT MONO (-120 4310);
FORCEPROP 2 LAST CDS_LIB pure_quanta
J 0
(-125 4400);
DISPLAY INVISIBLE (-125 4400);
FORCEPROP 1 LAST PATH I30
J 0
(-75 4575);
DISPLAY 0.978723 (-75 4575);
PAINT WHITE (-75 4575);
DISPLAY INVISIBLE (-75 4575);
FORCEPROP 0 LAST CDS_LOCATION R2243
J 0
(-75 4575);
DISPLAY 1.021277 (-75 4575);
DISPLAY INVISIBLE (-75 4575);
FORCEPROP 0 LAST $SEC 1
J 0
(-75 4575);
DISPLAY 0.680851 (-75 4575);
PAINT MONO (-75 4575);
DISPLAY INVISIBLE (-75 4575);
FORCEPROP 0 LAST CDS_SEC 1
J 0
(-75 4575);
DISPLAY 1.021277 (-75 4575);
DISPLAY INVISIBLE (-75 4575);
FORCEADD OFFPAGE..2
(1100 2400);
FORCEPROP 2 LAST $XR0 216 
J 0
(1289 2400);
DISPLAY 0.638298 (1289 2400);
PAINT MONO (1289 2400);
FORCEPROP 2 LAST CDS_LIB standard
J 0
(1100 2400);
PAINT MONO (1100 2400);
DISPLAY INVISIBLE (1100 2400);
FORCEPROP 1 LAST OFFPAGE TRUE
J 0
(1425 2275);
DISPLAY 0.872340 (1425 2275);
DISPLAY INVISIBLE (1425 2275);
FORCEPROP 1 LAST COMMENT_BODY TRUE
J 0
(1055 2305);
DISPLAY 0.872340 (1055 2305);
PAINT GREEN (1055 2305);
DISPLAY INVISIBLE (1055 2305);
FORCEPROP 2 LAST PATH I31
J 0
(1300 2450);
DISPLAY 1.021277 (1300 2450);
DISPLAY INVISIBLE (1300 2450);
FORCEADD OFFPAGE..2
(1100 2475);
FORCEPROP 2 LAST $XR0 216 
J 0
(1289 2475);
DISPLAY 0.638298 (1289 2475);
PAINT MONO (1289 2475);
FORCEPROP 2 LAST CDS_LIB standard
J 0
(1100 2475);
PAINT MONO (1100 2475);
DISPLAY INVISIBLE (1100 2475);
FORCEPROP 1 LAST OFFPAGE TRUE
J 0
(1425 2350);
DISPLAY 0.872340 (1425 2350);
DISPLAY INVISIBLE (1425 2350);
FORCEPROP 1 LAST COMMENT_BODY TRUE
J 0
(1055 2380);
DISPLAY 0.872340 (1055 2380);
PAINT GREEN (1055 2380);
DISPLAY INVISIBLE (1055 2380);
FORCEPROP 2 LAST PATH I32
J 0
(1300 2525);
DISPLAY 1.021277 (1300 2525);
DISPLAY INVISIBLE (1300 2525);
FORCEADD OFFPAGE..2
(1100 2550);
FORCEPROP 2 LAST $XR0 216 
J 0
(1289 2550);
DISPLAY 0.638298 (1289 2550);
PAINT MONO (1289 2550);
FORCEPROP 2 LAST CDS_LIB standard
J 0
(1100 2550);
PAINT MONO (1100 2550);
DISPLAY INVISIBLE (1100 2550);
FORCEPROP 1 LAST OFFPAGE TRUE
J 0
(1425 2425);
DISPLAY 0.872340 (1425 2425);
DISPLAY INVISIBLE (1425 2425);
FORCEPROP 1 LAST COMMENT_BODY TRUE
J 0
(1055 2455);
DISPLAY 0.872340 (1055 2455);
PAINT GREEN (1055 2455);
DISPLAY INVISIBLE (1055 2455);
FORCEPROP 2 LAST PATH I33
J 0
(1300 2600);
DISPLAY 1.021277 (1300 2600);
DISPLAY INVISIBLE (1300 2600);
FORCEADD OFFPAGE..2
(1100 2625);
FORCEPROP 2 LAST $XR0 216 
J 0
(1289 2625);
DISPLAY 0.638298 (1289 2625);
PAINT MONO (1289 2625);
FORCEPROP 2 LAST CDS_LIB standard
J 0
(1100 2625);
PAINT MONO (1100 2625);
DISPLAY INVISIBLE (1100 2625);
FORCEPROP 1 LAST OFFPAGE TRUE
J 0
(1425 2500);
DISPLAY 0.872340 (1425 2500);
DISPLAY INVISIBLE (1425 2500);
FORCEPROP 1 LAST COMMENT_BODY TRUE
J 0
(1055 2530);
DISPLAY 0.872340 (1055 2530);
PAINT GREEN (1055 2530);
DISPLAY INVISIBLE (1055 2530);
FORCEPROP 2 LAST PATH I34
J 0
(1300 2675);
DISPLAY 1.021277 (1300 2675);
DISPLAY INVISIBLE (1300 2675);
FORCEADD Q_RES..2
(-850 2075);
FORCEPROP 1 LAST PART_NUMBER CS21002FB06
J 0
(-810 1950);
DISPLAY 0.510638 (-810 1950);
DISPLAY INVISIBLE (-810 1950);
FORCEPROP 1 LAST PACK_TYPE 0402LF
J 0
(-810 1950);
DISPLAY 0.638298 (-810 1950);
FORCEPROP 1 LAST MATERIAL CHIP
J 0
(-810 2000);
DISPLAY 0.638298 (-810 2000);
FORCEPROP 1 LAST VALUE 1K
J 0
(-805 2150);
DISPLAY 0.638298 (-805 2150);
FORCEPROP 1 LAST TOLERANCE 1%
J 0
(-805 2100);
DISPLAY 0.638298 (-805 2100);
FORCEPROP 1 LAST WATTAGE 1/16W
J 0
(-810 2050);
DISPLAY 0.638298 (-810 2050);
FORCEPROP 1 LAST $LOCATION R4592
J 0
(-805 2200);
DISPLAY 0.978723 (-805 2200);
FORCEPROP 1 LASTPIN (-850 2175) $PN 1
J 0
(-845 2137);
DISPLAY 0.787234 (-845 2137);
PAINT MONO (-845 2137);
FORCEPROP 1 LASTPIN (-850 1975) $PN 2
J 0
(-845 1985);
DISPLAY 0.787234 (-845 1985);
PAINT MONO (-845 1985);
FORCEPROP 2 LAST CDS_LIB pure_quanta
J 0
(-850 2075);
DISPLAY INVISIBLE (-850 2075);
FORCEPROP 1 LAST PATH I4
J 0
(-800 2250);
DISPLAY 0.978723 (-800 2250);
PAINT WHITE (-800 2250);
DISPLAY INVISIBLE (-800 2250);
FORCEPROP 0 LAST CDS_LOCATION R4592
J 0
(-800 2250);
DISPLAY 1.021277 (-800 2250);
DISPLAY INVISIBLE (-800 2250);
FORCEPROP 0 LAST $SEC 1
J 0
(-800 2250);
DISPLAY 0.680851 (-800 2250);
PAINT MONO (-800 2250);
DISPLAY INVISIBLE (-800 2250);
FORCEPROP 0 LAST CDS_SEC 1
J 0
(-800 2250);
DISPLAY 1.021277 (-800 2250);
DISPLAY INVISIBLE (-800 2250);
FORCEADD Q_RES..2
(-675 5225);
FORCEPROP 1 LAST PART_NUMBER CS31002FB08
J 0
(-635 5100);
DISPLAY 0.510638 (-635 5100);
DISPLAY INVISIBLE (-635 5100);
FORCEPROP 1 LAST VALUE 10K
J 0
(-630 5300);
DISPLAY 0.638298 (-630 5300);
FORCEPROP 1 LAST PACK_TYPE 0402LF
J 0
(-635 5100);
DISPLAY 0.638298 (-635 5100);
FORCEPROP 1 LAST MATERIAL EMPTY
J 0
(-635 5150);
DISPLAY 0.638298 (-635 5150);
PAINT RED (-635 5150);
FORCEPROP 1 LAST WATTAGE 1/16W
J 0
(-635 5200);
DISPLAY 0.638298 (-635 5200);
FORCEPROP 1 LAST TOLERANCE 1%
J 0
(-630 5250);
DISPLAY 0.638298 (-630 5250);
FORCEPROP 1 LAST $LOCATION R2979
J 0
(-630 5350);
DISPLAY 0.978723 (-630 5350);
FORCEPROP 1 LASTPIN (-675 5325) $PN 1
J 0
(-670 5287);
DISPLAY 0.787234 (-670 5287);
PAINT MONO (-670 5287);
FORCEPROP 1 LASTPIN (-675 5125) $PN 2
J 0
(-670 5135);
DISPLAY 0.787234 (-670 5135);
PAINT MONO (-670 5135);
FORCEPROP 2 LAST CDS_LIB pure_quanta
J 0
(-675 5225);
DISPLAY INVISIBLE (-675 5225);
FORCEPROP 1 LAST PATH I48
J 0
(-625 5400);
DISPLAY 0.978723 (-625 5400);
PAINT WHITE (-625 5400);
DISPLAY INVISIBLE (-625 5400);
FORCEPROP 0 LAST CDS_LOCATION R2979
J 0
(-625 5400);
DISPLAY 1.021277 (-625 5400);
DISPLAY INVISIBLE (-625 5400);
FORCEPROP 0 LAST $SEC 1
J 0
(-625 5400);
DISPLAY 0.680851 (-625 5400);
PAINT MONO (-625 5400);
DISPLAY INVISIBLE (-625 5400);
FORCEPROP 0 LAST CDS_SEC 1
J 0
(-625 5400);
DISPLAY 1.021277 (-625 5400);
DISPLAY INVISIBLE (-625 5400);
FORCEADD Q_RES..2
(-400 5225);
FORCEPROP 1 LAST PART_NUMBER CS31002FB08
J 0
(-360 5100);
DISPLAY 0.510638 (-360 5100);
DISPLAY INVISIBLE (-360 5100);
FORCEPROP 1 LAST PACK_TYPE 0402LF
J 0
(-360 5100);
DISPLAY 0.638298 (-360 5100);
FORCEPROP 1 LAST MATERIAL EMPTY
J 0
(-360 5150);
DISPLAY 0.638298 (-360 5150);
PAINT RED (-360 5150);
FORCEPROP 1 LAST WATTAGE 1/16W
J 0
(-360 5200);
DISPLAY 0.638298 (-360 5200);
FORCEPROP 1 LAST TOLERANCE 1%
J 0
(-355 5250);
DISPLAY 0.638298 (-355 5250);
FORCEPROP 1 LAST VALUE 10K
J 0
(-355 5300);
DISPLAY 0.638298 (-355 5300);
FORCEPROP 1 LAST $LOCATION R2240
J 0
(-355 5350);
DISPLAY 0.978723 (-355 5350);
FORCEPROP 1 LASTPIN (-400 5325) $PN 1
J 0
(-395 5287);
DISPLAY 0.787234 (-395 5287);
PAINT MONO (-395 5287);
FORCEPROP 1 LASTPIN (-400 5125) $PN 2
J 0
(-395 5135);
DISPLAY 0.787234 (-395 5135);
PAINT MONO (-395 5135);
FORCEPROP 2 LAST CDS_LIB pure_quanta
J 0
(-400 5225);
DISPLAY INVISIBLE (-400 5225);
FORCEPROP 1 LAST PATH I49
J 0
(-350 5400);
DISPLAY 0.978723 (-350 5400);
PAINT WHITE (-350 5400);
DISPLAY INVISIBLE (-350 5400);
FORCEPROP 0 LAST CDS_LOCATION R2240
J 0
(-350 5400);
DISPLAY 1.021277 (-350 5400);
DISPLAY INVISIBLE (-350 5400);
FORCEPROP 0 LAST $SEC 1
J 0
(-350 5400);
DISPLAY 0.680851 (-350 5400);
PAINT MONO (-350 5400);
DISPLAY INVISIBLE (-350 5400);
FORCEPROP 0 LAST CDS_SEC 1
J 0
(-350 5400);
DISPLAY 1.021277 (-350 5400);
DISPLAY INVISIBLE (-350 5400);
FORCEADD Q_RES..2
(-1125 2900);
FORCEPROP 1 LAST PART_NUMBER CS31002FB08
J 0
(-1085 2775);
DISPLAY 0.510638 (-1085 2775);
DISPLAY INVISIBLE (-1085 2775);
FORCEPROP 1 LAST MATERIAL EMPTY
J 0
(-1085 2825);
DISPLAY 0.638298 (-1085 2825);
PAINT RED (-1085 2825);
FORCEPROP 1 LAST WATTAGE 1/16W
J 0
(-1085 2875);
DISPLAY 0.638298 (-1085 2875);
FORCEPROP 1 LAST PACK_TYPE 0402LF
J 0
(-1085 2775);
DISPLAY 0.638298 (-1085 2775);
FORCEPROP 1 LAST TOLERANCE 1%
J 0
(-1080 2925);
DISPLAY 0.638298 (-1080 2925);
FORCEPROP 1 LAST VALUE 10K
J 0
(-1080 2975);
DISPLAY 0.638298 (-1080 2975);
FORCEPROP 1 LAST $LOCATION R4580
J 0
(-1080 3025);
DISPLAY 0.978723 (-1080 3025);
FORCEPROP 1 LASTPIN (-1125 3000) $PN 1
J 0
(-1120 2962);
DISPLAY 0.787234 (-1120 2962);
PAINT MONO (-1120 2962);
FORCEPROP 1 LASTPIN (-1125 2800) $PN 2
J 0
(-1120 2810);
DISPLAY 0.787234 (-1120 2810);
PAINT MONO (-1120 2810);
FORCEPROP 2 LAST CDS_LIB pure_quanta
J 0
(-1125 2900);
DISPLAY INVISIBLE (-1125 2900);
FORCEPROP 1 LAST PATH I5
J 0
(-1075 3075);
DISPLAY 0.978723 (-1075 3075);
PAINT WHITE (-1075 3075);
DISPLAY INVISIBLE (-1075 3075);
FORCEPROP 0 LAST CDS_LOCATION R4580
J 0
(-1075 3075);
DISPLAY 1.021277 (-1075 3075);
DISPLAY INVISIBLE (-1075 3075);
FORCEPROP 0 LAST $SEC 1
J 0
(-1075 3075);
DISPLAY 0.680851 (-1075 3075);
PAINT MONO (-1075 3075);
DISPLAY INVISIBLE (-1075 3075);
FORCEPROP 0 LAST CDS_SEC 1
J 0
(-1075 3075);
DISPLAY 1.021277 (-1075 3075);
DISPLAY INVISIBLE (-1075 3075);
FORCEADD Q_RES..2
(-125 5225);
FORCEPROP 1 LAST PART_NUMBER CS31002FB08
J 0
(-85 5100);
DISPLAY 0.510638 (-85 5100);
DISPLAY INVISIBLE (-85 5100);
FORCEPROP 1 LAST VALUE 10K
J 0
(-80 5300);
DISPLAY 0.638298 (-80 5300);
FORCEPROP 1 LAST MATERIAL EMPTY
J 0
(-85 5150);
DISPLAY 0.638298 (-85 5150);
PAINT RED (-85 5150);
FORCEPROP 1 LAST PACK_TYPE 0402LF
J 0
(-85 5050);
DISPLAY 0.638298 (-85 5050);
FORCEPROP 1 LAST TOLERANCE 1%
J 0
(-80 5250);
DISPLAY 0.638298 (-80 5250);
FORCEPROP 1 LAST WATTAGE 1/16W
J 0
(-85 5200);
DISPLAY 0.638298 (-85 5200);
FORCEPROP 1 LAST $LOCATION R2242
J 0
(-80 5350);
DISPLAY 0.978723 (-80 5350);
FORCEPROP 1 LASTPIN (-125 5325) $PN 1
J 0
(-120 5287);
DISPLAY 0.787234 (-120 5287);
PAINT MONO (-120 5287);
FORCEPROP 1 LASTPIN (-125 5125) $PN 2
J 0
(-120 5135);
DISPLAY 0.787234 (-120 5135);
PAINT MONO (-120 5135);
FORCEPROP 2 LAST CDS_LIB pure_quanta
J 0
(-125 5225);
DISPLAY INVISIBLE (-125 5225);
FORCEPROP 1 LAST PATH I50
J 0
(-75 5400);
DISPLAY 0.978723 (-75 5400);
PAINT WHITE (-75 5400);
DISPLAY INVISIBLE (-75 5400);
FORCEPROP 0 LAST CDS_LOCATION R2242
J 0
(-75 5400);
DISPLAY 1.021277 (-75 5400);
DISPLAY INVISIBLE (-75 5400);
FORCEPROP 0 LAST $SEC 1
J 0
(-75 5400);
DISPLAY 0.680851 (-75 5400);
PAINT MONO (-75 5400);
DISPLAY INVISIBLE (-75 5400);
FORCEPROP 0 LAST CDS_SEC 1
J 0
(-75 5400);
DISPLAY 1.021277 (-75 5400);
DISPLAY INVISIBLE (-75 5400);
FORCEADD OFFPAGE..2
(1000 4650);
FORCEPROP 2 LAST $XR0 184 
J 0
(1189 4650);
DISPLAY 0.638298 (1189 4650);
PAINT MONO (1189 4650);
FORCEPROP 2 LAST CDS_LIB standard
J 0
(1000 4650);
PAINT MONO (1000 4650);
DISPLAY INVISIBLE (1000 4650);
FORCEPROP 1 LAST OFFPAGE TRUE
J 0
(1325 4525);
DISPLAY 0.872340 (1325 4525);
DISPLAY INVISIBLE (1325 4525);
FORCEPROP 1 LAST COMMENT_BODY TRUE
J 0
(955 4555);
DISPLAY 0.872340 (955 4555);
PAINT GREEN (955 4555);
DISPLAY INVISIBLE (955 4555);
FORCEPROP 2 LAST PATH I51
J 0
(1200 4700);
DISPLAY 1.021277 (1200 4700);
DISPLAY INVISIBLE (1200 4700);
FORCEADD OFFPAGE..2
(1000 4725);
FORCEPROP 2 LAST $XR0 184 
J 0
(1189 4725);
DISPLAY 0.638298 (1189 4725);
PAINT MONO (1189 4725);
FORCEPROP 2 LAST CDS_LIB standard
J 0
(1000 4725);
PAINT MONO (1000 4725);
DISPLAY INVISIBLE (1000 4725);
FORCEPROP 1 LAST OFFPAGE TRUE
J 0
(1325 4600);
DISPLAY 0.872340 (1325 4600);
DISPLAY INVISIBLE (1325 4600);
FORCEPROP 1 LAST COMMENT_BODY TRUE
J 0
(955 4630);
DISPLAY 0.872340 (955 4630);
PAINT GREEN (955 4630);
DISPLAY INVISIBLE (955 4630);
FORCEPROP 2 LAST PATH I52
J 0
(1200 4775);
DISPLAY 1.021277 (1200 4775);
DISPLAY INVISIBLE (1200 4775);
FORCEADD OFFPAGE..2
(1000 4800);
FORCEPROP 2 LAST $XR0 184 
J 0
(1189 4800);
DISPLAY 0.638298 (1189 4800);
PAINT MONO (1189 4800);
FORCEPROP 2 LAST CDS_LIB standard
J 0
(1000 4800);
PAINT MONO (1000 4800);
DISPLAY INVISIBLE (1000 4800);
FORCEPROP 1 LAST OFFPAGE TRUE
J 0
(1325 4675);
DISPLAY 0.872340 (1325 4675);
DISPLAY INVISIBLE (1325 4675);
FORCEPROP 1 LAST COMMENT_BODY TRUE
J 0
(955 4705);
DISPLAY 0.872340 (955 4705);
PAINT GREEN (955 4705);
DISPLAY INVISIBLE (955 4705);
FORCEPROP 2 LAST PATH I53
J 0
(1200 4850);
DISPLAY 1.021277 (1200 4850);
DISPLAY INVISIBLE (1200 4850);
FORCEADD OFFPAGE..2
(1000 4875);
FORCEPROP 2 LAST $XR0 184 
J 0
(1189 4875);
DISPLAY 0.638298 (1189 4875);
PAINT MONO (1189 4875);
FORCEPROP 2 LAST CDS_LIB standard
J 0
(1000 4875);
PAINT MONO (1000 4875);
DISPLAY INVISIBLE (1000 4875);
FORCEPROP 1 LAST OFFPAGE TRUE
J 0
(1325 4750);
DISPLAY 0.872340 (1325 4750);
DISPLAY INVISIBLE (1325 4750);
FORCEPROP 1 LAST COMMENT_BODY TRUE
J 0
(955 4780);
DISPLAY 0.872340 (955 4780);
PAINT GREEN (955 4780);
DISPLAY INVISIBLE (955 4780);
FORCEPROP 2 LAST PATH I54
J 0
(1200 4925);
DISPLAY 1.021277 (1200 4925);
DISPLAY INVISIBLE (1200 4925);
FORCEADD OFFPAGE..2
(1000 4950);
FORCEPROP 2 LAST $XR0 184 
J 0
(1189 4950);
DISPLAY 0.638298 (1189 4950);
PAINT MONO (1189 4950);
FORCEPROP 2 LAST CDS_LIB standard
J 0
(1000 4950);
PAINT MONO (1000 4950);
DISPLAY INVISIBLE (1000 4950);
FORCEPROP 1 LAST OFFPAGE TRUE
J 0
(1325 4825);
DISPLAY 0.872340 (1325 4825);
DISPLAY INVISIBLE (1325 4825);
FORCEPROP 1 LAST COMMENT_BODY TRUE
J 0
(955 4855);
DISPLAY 0.872340 (955 4855);
PAINT GREEN (955 4855);
DISPLAY INVISIBLE (955 4855);
FORCEPROP 2 LAST PATH I55
J 0
(1200 5000);
DISPLAY 1.021277 (1200 5000);
DISPLAY INVISIBLE (1200 5000);
FORCEADD UNIVERSAL_GND..1
(2150 1800);
FORCEPROP 3 LASTPIN (2150 1850) SIG_NAME GND\g
J 0
(2160 1860);
DISPLAY 0.659574 (2160 1860);
PAINT MONO (2160 1860);
DISPLAY INVISIBLE (2160 1860);
FORCEPROP 2 LAST CDS_LIB logical_power
J 0
(2150 1800);
PAINT MONO (2150 1800);
DISPLAY INVISIBLE (2150 1800);
FORCEPROP 1 LAST HDL_POWER GND
J 1
(2175 1725);
DISPLAY 0.872340 (2175 1725);
PAINT GREEN (2175 1725);
DISPLAY INVISIBLE (2175 1725);
FORCEPROP 1 LAST PATH I56
J 0
(2225 1800);
DISPLAY 0.872340 (2225 1800);
PAINT AQUA (2225 1800);
DISPLAY INVISIBLE (2225 1800);
FORCEADD UNIVERSAL_GND..1
(1875 1800);
FORCEPROP 3 LASTPIN (1875 1850) SIG_NAME GND\g
J 0
(1885 1860);
DISPLAY 0.659574 (1885 1860);
PAINT MONO (1885 1860);
DISPLAY INVISIBLE (1885 1860);
FORCEPROP 2 LAST CDS_LIB logical_power
J 0
(1875 1800);
PAINT MONO (1875 1800);
DISPLAY INVISIBLE (1875 1800);
FORCEPROP 1 LAST HDL_POWER GND
J 1
(1900 1725);
DISPLAY 0.872340 (1900 1725);
PAINT GREEN (1900 1725);
DISPLAY INVISIBLE (1900 1725);
FORCEPROP 1 LAST PATH I57
J 0
(1950 1800);
DISPLAY 0.872340 (1950 1800);
PAINT AQUA (1950 1800);
DISPLAY INVISIBLE (1950 1800);
FORCEADD Q_RES..2
(1875 2025);
FORCEPROP 1 LAST PART_NUMBER CS21002FB06
J 0
(1915 1900);
DISPLAY 0.510638 (1915 1900);
DISPLAY INVISIBLE (1915 1900);
FORCEPROP 1 LAST WATTAGE 1/16W
J 0
(1915 2000);
DISPLAY 0.638298 (1915 2000);
FORCEPROP 1 LAST VALUE 1K
J 0
(1920 2100);
DISPLAY 0.638298 (1920 2100);
FORCEPROP 1 LAST PACK_TYPE 0402LF
J 0
(1915 1900);
DISPLAY 0.638298 (1915 1900);
FORCEPROP 1 LAST MATERIAL EMPTY
J 0
(1915 1950);
DISPLAY 0.638298 (1915 1950);
FORCEPROP 1 LAST TOLERANCE 1%
J 0
(1920 2050);
DISPLAY 0.638298 (1920 2050);
FORCEPROP 1 LAST $LOCATION R4588
J 0
(1920 2150);
DISPLAY 0.978723 (1920 2150);
FORCEPROP 1 LASTPIN (1875 2125) $PN 1
J 0
(1880 2087);
DISPLAY 0.787234 (1880 2087);
PAINT MONO (1880 2087);
FORCEPROP 1 LASTPIN (1875 1925) $PN 2
J 0
(1880 1935);
DISPLAY 0.787234 (1880 1935);
PAINT MONO (1880 1935);
FORCEPROP 2 LAST CDS_LIB pure_quanta
J 0
(1875 2025);
DISPLAY INVISIBLE (1875 2025);
FORCEPROP 1 LAST PATH I58
J 0
(1925 2200);
DISPLAY 0.978723 (1925 2200);
PAINT WHITE (1925 2200);
DISPLAY INVISIBLE (1925 2200);
FORCEPROP 0 LAST CDS_LOCATION R4588
J 0
(1925 2200);
DISPLAY 1.021277 (1925 2200);
DISPLAY INVISIBLE (1925 2200);
FORCEPROP 0 LAST $SEC 1
J 0
(1925 2200);
DISPLAY 0.680851 (1925 2200);
PAINT MONO (1925 2200);
DISPLAY INVISIBLE (1925 2200);
FORCEPROP 0 LAST CDS_SEC 1
J 0
(1925 2200);
DISPLAY 1.021277 (1925 2200);
DISPLAY INVISIBLE (1925 2200);
FORCEADD Q_RES..2
(2150 2025);
FORCEPROP 1 LAST PART_NUMBER CS21002FB06
J 0
(2190 1900);
DISPLAY 0.510638 (2190 1900);
DISPLAY INVISIBLE (2190 1900);
FORCEPROP 1 LAST MATERIAL EMPTY
J 0
(2190 1950);
DISPLAY 0.638298 (2190 1950);
PAINT PINK (2190 1950);
FORCEPROP 1 LAST TOLERANCE 1%
J 0
(2195 2050);
DISPLAY 0.638298 (2195 2050);
FORCEPROP 1 LAST PACK_TYPE 0402LF
J 0
(2190 1900);
DISPLAY 0.638298 (2190 1900);
FORCEPROP 1 LAST WATTAGE 1/16W
J 0
(2190 2000);
DISPLAY 0.638298 (2190 2000);
FORCEPROP 1 LAST VALUE 1K
J 0
(2195 2100);
DISPLAY 0.638298 (2195 2100);
FORCEPROP 1 LAST $LOCATION R4590
J 0
(2195 2150);
DISPLAY 0.978723 (2195 2150);
FORCEPROP 1 LASTPIN (2150 2125) $PN 1
J 0
(2155 2087);
DISPLAY 0.787234 (2155 2087);
PAINT MONO (2155 2087);
FORCEPROP 1 LASTPIN (2150 1925) $PN 2
J 0
(2155 1935);
DISPLAY 0.787234 (2155 1935);
PAINT MONO (2155 1935);
FORCEPROP 2 LAST CDS_LIB pure_quanta
J 0
(2150 2025);
DISPLAY INVISIBLE (2150 2025);
FORCEPROP 1 LAST PATH I59
J 0
(2200 2200);
DISPLAY 0.978723 (2200 2200);
PAINT WHITE (2200 2200);
DISPLAY INVISIBLE (2200 2200);
FORCEPROP 0 LAST CDS_LOCATION R4590
J 0
(2200 2200);
DISPLAY 1.021277 (2200 2200);
DISPLAY INVISIBLE (2200 2200);
FORCEPROP 0 LAST $SEC 1
J 0
(2200 2200);
DISPLAY 0.680851 (2200 2200);
PAINT MONO (2200 2200);
DISPLAY INVISIBLE (2200 2200);
FORCEPROP 0 LAST CDS_SEC 1
J 0
(2200 2200);
DISPLAY 1.021277 (2200 2200);
DISPLAY INVISIBLE (2200 2200);
FORCEADD Q_RES..2
(-850 2900);
FORCEPROP 1 LAST PART_NUMBER CS31002FB08
J 0
(-810 2775);
DISPLAY 0.510638 (-810 2775);
DISPLAY INVISIBLE (-810 2775);
FORCEPROP 1 LAST PACK_TYPE 0402LF
J 0
(-810 2775);
DISPLAY 0.638298 (-810 2775);
FORCEPROP 1 LAST MATERIAL EMPTY
J 0
(-810 2825);
DISPLAY 0.638298 (-810 2825);
PAINT RED (-810 2825);
FORCEPROP 1 LAST WATTAGE 1/16W
J 0
(-810 2875);
DISPLAY 0.638298 (-810 2875);
FORCEPROP 1 LAST VALUE 10K
J 0
(-805 2975);
DISPLAY 0.638298 (-805 2975);
FORCEPROP 1 LAST TOLERANCE 1%
J 0
(-805 2925);
DISPLAY 0.638298 (-805 2925);
FORCEPROP 1 LAST $LOCATION R4591
J 0
(-805 3025);
DISPLAY 0.978723 (-805 3025);
FORCEPROP 1 LASTPIN (-850 3000) $PN 1
J 0
(-845 2962);
DISPLAY 0.787234 (-845 2962);
PAINT MONO (-845 2962);
FORCEPROP 1 LASTPIN (-850 2800) $PN 2
J 0
(-845 2810);
DISPLAY 0.787234 (-845 2810);
PAINT MONO (-845 2810);
FORCEPROP 2 LAST CDS_LIB pure_quanta
J 0
(-850 2900);
DISPLAY INVISIBLE (-850 2900);
FORCEPROP 1 LAST PATH I6
J 0
(-800 3075);
DISPLAY 0.978723 (-800 3075);
PAINT WHITE (-800 3075);
DISPLAY INVISIBLE (-800 3075);
FORCEPROP 0 LAST CDS_LOCATION R4591
J 0
(-800 3075);
DISPLAY 1.021277 (-800 3075);
DISPLAY INVISIBLE (-800 3075);
FORCEPROP 0 LAST $SEC 1
J 0
(-800 3075);
DISPLAY 0.680851 (-800 3075);
PAINT MONO (-800 3075);
DISPLAY INVISIBLE (-800 3075);
FORCEPROP 0 LAST CDS_SEC 1
J 0
(-800 3075);
DISPLAY 1.021277 (-800 3075);
DISPLAY INVISIBLE (-800 3075);
FORCEADD UNIVERSAL_GND..1
(2425 1800);
FORCEPROP 3 LASTPIN (2425 1850) SIG_NAME GND\g
J 0
(2435 1860);
DISPLAY 0.659574 (2435 1860);
PAINT MONO (2435 1860);
DISPLAY INVISIBLE (2435 1860);
FORCEPROP 2 LAST CDS_LIB logical_power
J 0
(2425 1800);
PAINT MONO (2425 1800);
DISPLAY INVISIBLE (2425 1800);
FORCEPROP 1 LAST HDL_POWER GND
J 1
(2450 1725);
DISPLAY 0.872340 (2450 1725);
PAINT GREEN (2450 1725);
DISPLAY INVISIBLE (2450 1725);
FORCEPROP 1 LAST PATH I60
J 0
(2500 1800);
DISPLAY 0.872340 (2500 1800);
PAINT AQUA (2500 1800);
DISPLAY INVISIBLE (2500 1800);
FORCEADD Q_RES..2
(2425 2025);
FORCEPROP 1 LAST PART_NUMBER CS21002FB06
J 0
(2465 1900);
DISPLAY 0.510638 (2465 1900);
DISPLAY INVISIBLE (2465 1900);
FORCEPROP 1 LAST PACK_TYPE 0402LF
J 0
(2465 1850);
DISPLAY 0.638298 (2465 1850);
FORCEPROP 1 LAST WATTAGE 1/16W
J 0
(2465 2000);
DISPLAY 0.638298 (2465 2000);
FORCEPROP 1 LAST VALUE 1K
J 0
(2470 2100);
DISPLAY 0.638298 (2470 2100);
FORCEPROP 1 LAST MATERIAL EMPTY
J 0
(2465 1950);
DISPLAY 0.638298 (2465 1950);
PAINT RED (2465 1950);
FORCEPROP 1 LAST TOLERANCE 1%
J 0
(2470 2050);
DISPLAY 0.638298 (2470 2050);
FORCEPROP 1 LAST $LOCATION R4596
J 0
(2470 2150);
DISPLAY 0.978723 (2470 2150);
FORCEPROP 1 LASTPIN (2425 2125) $PN 1
J 0
(2430 2087);
DISPLAY 0.787234 (2430 2087);
PAINT MONO (2430 2087);
FORCEPROP 1 LASTPIN (2425 1925) $PN 2
J 0
(2430 1935);
DISPLAY 0.787234 (2430 1935);
PAINT MONO (2430 1935);
FORCEPROP 1 LAST PATH I61
J 0
(2475 2200);
DISPLAY 0.978723 (2475 2200);
PAINT WHITE (2475 2200);
DISPLAY INVISIBLE (2475 2200);
FORCEPROP 2 LAST CDS_LIB pure_quanta
J 0
(2425 2025);
DISPLAY INVISIBLE (2425 2025);
FORCEPROP 0 LAST CDS_LOCATION R4596
J 0
(2475 2200);
DISPLAY 1.021277 (2475 2200);
DISPLAY INVISIBLE (2475 2200);
FORCEPROP 0 LAST $SEC 1
J 0
(2475 2200);
DISPLAY 0.680851 (2475 2200);
PAINT MONO (2475 2200);
DISPLAY INVISIBLE (2475 2200);
FORCEPROP 0 LAST CDS_SEC 1
J 0
(2475 2200);
DISPLAY 1.021277 (2475 2200);
DISPLAY INVISIBLE (2475 2200);
FORCEADD Q_RES..2
(1875 2675);
FORCEPROP 1 LAST PART_NUMBER CS31002FB08
J 0
(1915 2550);
DISPLAY 0.510638 (1915 2550);
DISPLAY INVISIBLE (1915 2550);
FORCEPROP 1 LAST WATTAGE 1/16W
J 0
(1915 2650);
DISPLAY 0.638298 (1915 2650);
FORCEPROP 1 LAST PACK_TYPE 0402LF
J 0
(1915 2550);
DISPLAY 0.638298 (1915 2550);
FORCEPROP 1 LAST TOLERANCE 1%
J 0
(1920 2700);
DISPLAY 0.638298 (1920 2700);
FORCEPROP 1 LAST MATERIAL CHIP
J 0
(1915 2600);
DISPLAY 0.638298 (1915 2600);
PAINT RED (1915 2600);
FORCEPROP 1 LAST VALUE 10K
J 0
(1920 2750);
DISPLAY 0.638298 (1920 2750);
FORCEPROP 1 LAST $LOCATION R4586
J 0
(1920 2800);
DISPLAY 0.978723 (1920 2800);
FORCEPROP 1 LASTPIN (1875 2775) $PN 1
J 0
(1880 2737);
DISPLAY 0.787234 (1880 2737);
PAINT MONO (1880 2737);
FORCEPROP 1 LASTPIN (1875 2575) $PN 2
J 0
(1880 2585);
DISPLAY 0.787234 (1880 2585);
PAINT MONO (1880 2585);
FORCEPROP 2 LAST CDS_LIB pure_quanta
J 0
(1875 2675);
DISPLAY INVISIBLE (1875 2675);
FORCEPROP 1 LAST PATH I62
J 0
(1925 2850);
DISPLAY 0.978723 (1925 2850);
PAINT WHITE (1925 2850);
DISPLAY INVISIBLE (1925 2850);
FORCEPROP 0 LAST CDS_LOCATION R4586
J 0
(1925 2850);
DISPLAY 1.021277 (1925 2850);
DISPLAY INVISIBLE (1925 2850);
FORCEPROP 0 LAST $SEC 1
J 0
(1925 2850);
DISPLAY 0.680851 (1925 2850);
PAINT MONO (1925 2850);
DISPLAY INVISIBLE (1925 2850);
FORCEPROP 0 LAST CDS_SEC 1
J 0
(1925 2850);
DISPLAY 1.021277 (1925 2850);
DISPLAY INVISIBLE (1925 2850);
FORCEADD Q_RES..2
(2150 2675);
FORCEPROP 1 LAST PART_NUMBER CS31002FB08
J 0
(2190 2550);
DISPLAY 0.510638 (2190 2550);
DISPLAY INVISIBLE (2190 2550);
FORCEPROP 1 LAST VALUE 10K
J 0
(2195 2750);
DISPLAY 0.638298 (2195 2750);
FORCEPROP 1 LAST MATERIAL CHIP
J 0
(2190 2600);
DISPLAY 0.638298 (2190 2600);
PAINT RED (2190 2600);
FORCEPROP 1 LAST PACK_TYPE 0402LF
J 0
(2190 2550);
DISPLAY 0.638298 (2190 2550);
FORCEPROP 1 LAST TOLERANCE 1%
J 0
(2195 2700);
DISPLAY 0.638298 (2195 2700);
FORCEPROP 1 LAST WATTAGE 1/16W
J 0
(2190 2650);
DISPLAY 0.638298 (2190 2650);
FORCEPROP 1 LAST $LOCATION R4589
J 0
(2195 2800);
DISPLAY 0.978723 (2195 2800);
FORCEPROP 1 LASTPIN (2150 2775) $PN 1
J 0
(2155 2737);
DISPLAY 0.787234 (2155 2737);
PAINT MONO (2155 2737);
FORCEPROP 1 LASTPIN (2150 2575) $PN 2
J 0
(2155 2585);
DISPLAY 0.787234 (2155 2585);
PAINT MONO (2155 2585);
FORCEPROP 2 LAST CDS_LIB pure_quanta
J 0
(2150 2675);
DISPLAY INVISIBLE (2150 2675);
FORCEPROP 1 LAST PATH I63
J 0
(2200 2850);
DISPLAY 0.978723 (2200 2850);
PAINT WHITE (2200 2850);
DISPLAY INVISIBLE (2200 2850);
FORCEPROP 0 LAST CDS_LOCATION R4589
J 0
(2200 2850);
DISPLAY 1.021277 (2200 2850);
DISPLAY INVISIBLE (2200 2850);
FORCEPROP 0 LAST $SEC 1
J 0
(2200 2850);
DISPLAY 0.680851 (2200 2850);
PAINT MONO (2200 2850);
DISPLAY INVISIBLE (2200 2850);
FORCEPROP 0 LAST CDS_SEC 1
J 0
(2200 2850);
DISPLAY 1.021277 (2200 2850);
DISPLAY INVISIBLE (2200 2850);
FORCEADD UNIVERSAL_POWER..1
R 2
(1875 3050);
FORCEPROP 3 LASTPIN (1875 3000) SIG_NAME P3V3_AUX\g
J 0
(1885 3010);
DISPLAY 0.659574 (1885 3010);
PAINT MONO (1885 3010);
DISPLAY INVISIBLE (1885 3010);
FORCEPROP 1 LAST HDL_POWER P3V3_AUX
J 1
(1875 3100);
DISPLAY 0.723404 (1875 3100);
PAINT GREEN (1875 3100);
FORCEPROP 2 LAST CDS_LIB logical_power
J 0
(1875 3050);
DISPLAY INVISIBLE (1875 3050);
FORCEPROP 1 LAST PATH I64
J 2
(1825 3075);
DISPLAY 0.872340 (1825 3075);
PAINT AQUA (1825 3075);
DISPLAY INVISIBLE (1825 3075);
FORCEADD UNIVERSAL_GND..1
(1875 4275);
FORCEPROP 3 LASTPIN (1875 4325) SIG_NAME GND\g
J 0
(1885 4335);
DISPLAY 0.659574 (1885 4335);
PAINT MONO (1885 4335);
DISPLAY INVISIBLE (1885 4335);
FORCEPROP 2 LAST CDS_LIB logical_power
J 0
(1875 4275);
PAINT MONO (1875 4275);
DISPLAY INVISIBLE (1875 4275);
FORCEPROP 1 LAST HDL_POWER GND
J 1
(1900 4200);
DISPLAY 0.872340 (1900 4200);
PAINT GREEN (1900 4200);
DISPLAY INVISIBLE (1900 4200);
FORCEPROP 1 LAST PATH I65
J 0
(1950 4275);
DISPLAY 0.872340 (1950 4275);
PAINT AQUA (1950 4275);
DISPLAY INVISIBLE (1950 4275);
FORCEADD UNIVERSAL_GND..1
(2150 4275);
FORCEPROP 3 LASTPIN (2150 4325) SIG_NAME GND\g
J 0
(2160 4335);
DISPLAY 0.659574 (2160 4335);
PAINT MONO (2160 4335);
DISPLAY INVISIBLE (2160 4335);
FORCEPROP 2 LAST CDS_LIB logical_power
J 0
(2150 4275);
PAINT MONO (2150 4275);
DISPLAY INVISIBLE (2150 4275);
FORCEPROP 1 LAST HDL_POWER GND
J 1
(2175 4200);
DISPLAY 0.872340 (2175 4200);
PAINT GREEN (2175 4200);
DISPLAY INVISIBLE (2175 4200);
FORCEPROP 1 LAST PATH I66
J 0
(2225 4275);
DISPLAY 0.872340 (2225 4275);
PAINT AQUA (2225 4275);
DISPLAY INVISIBLE (2225 4275);
FORCEADD Q_RES..2
(2425 2675);
FORCEPROP 1 LAST PART_NUMBER CS31002FB08
J 0
(2465 2550);
DISPLAY 0.510638 (2465 2550);
DISPLAY INVISIBLE (2465 2550);
FORCEPROP 1 LAST MATERIAL CHIP
J 0
(2465 2600);
DISPLAY 0.638298 (2465 2600);
PAINT YELLOW (2465 2600);
FORCEPROP 1 LAST TOLERANCE 1%
J 0
(2470 2700);
DISPLAY 0.638298 (2470 2700);
FORCEPROP 1 LAST VALUE 10K
J 0
(2470 2750);
DISPLAY 0.638298 (2470 2750);
FORCEPROP 1 LAST WATTAGE 1/16W
J 0
(2465 2650);
DISPLAY 0.638298 (2465 2650);
FORCEPROP 1 LAST PACK_TYPE 0402LF
J 0
(2465 2500);
DISPLAY 0.638298 (2465 2500);
FORCEPROP 1 LAST $LOCATION R4579
J 0
(2470 2800);
DISPLAY 0.978723 (2470 2800);
FORCEPROP 1 LASTPIN (2425 2775) $PN 1
J 0
(2430 2737);
DISPLAY 0.787234 (2430 2737);
PAINT MONO (2430 2737);
FORCEPROP 1 LASTPIN (2425 2575) $PN 2
J 0
(2430 2585);
DISPLAY 0.787234 (2430 2585);
PAINT MONO (2430 2585);
FORCEPROP 2 LAST CDS_LIB pure_quanta
J 0
(2425 2675);
DISPLAY INVISIBLE (2425 2675);
FORCEPROP 1 LAST PATH I67
J 0
(2475 2850);
DISPLAY 0.978723 (2475 2850);
PAINT WHITE (2475 2850);
DISPLAY INVISIBLE (2475 2850);
FORCEPROP 0 LAST CDS_LOCATION R4579
J 0
(2475 2850);
DISPLAY 1.021277 (2475 2850);
DISPLAY INVISIBLE (2475 2850);
FORCEPROP 0 LAST $SEC 1
J 0
(2475 2850);
DISPLAY 0.680851 (2475 2850);
PAINT MONO (2475 2850);
DISPLAY INVISIBLE (2475 2850);
FORCEPROP 0 LAST CDS_SEC 1
J 0
(2475 2850);
DISPLAY 1.021277 (2475 2850);
DISPLAY INVISIBLE (2475 2850);
FORCEADD UNIVERSAL_GND..1
(2425 4275);
FORCEPROP 3 LASTPIN (2425 4325) SIG_NAME GND\g
J 0
(2435 4335);
DISPLAY 0.659574 (2435 4335);
PAINT MONO (2435 4335);
DISPLAY INVISIBLE (2435 4335);
FORCEPROP 2 LAST CDS_LIB logical_power
J 0
(2425 4275);
PAINT MONO (2425 4275);
DISPLAY INVISIBLE (2425 4275);
FORCEPROP 1 LAST HDL_POWER GND
J 1
(2450 4200);
DISPLAY 0.872340 (2450 4200);
PAINT GREEN (2450 4200);
DISPLAY INVISIBLE (2450 4200);
FORCEPROP 1 LAST PATH I68
J 0
(2500 4275);
DISPLAY 0.872340 (2500 4275);
PAINT AQUA (2500 4275);
DISPLAY INVISIBLE (2500 4275);
FORCEADD Q_RES..2
(1875 4500);
FORCEPROP 1 LAST PART_NUMBER CS21002FB06
J 0
(1915 4375);
DISPLAY 0.510638 (1915 4375);
DISPLAY INVISIBLE (1915 4375);
FORCEPROP 1 LAST VALUE 1K
J 0
(1920 4575);
DISPLAY 0.638298 (1920 4575);
FORCEPROP 1 LAST MATERIAL EMPTY
J 0
(1915 4425);
DISPLAY 0.638298 (1915 4425);
FORCEPROP 1 LAST WATTAGE 1/16W
J 0
(1915 4475);
DISPLAY 0.638298 (1915 4475);
FORCEPROP 1 LAST TOLERANCE 1%
J 0
(1920 4525);
DISPLAY 0.638298 (1920 4525);
FORCEPROP 1 LAST PACK_TYPE 0402LF
J 0
(1915 4375);
DISPLAY 0.638298 (1915 4375);
FORCEPROP 1 LAST $LOCATION R2973
J 0
(1920 4625);
DISPLAY 0.978723 (1920 4625);
FORCEPROP 1 LASTPIN (1875 4600) $PN 1
J 0
(1880 4562);
DISPLAY 0.787234 (1880 4562);
PAINT MONO (1880 4562);
FORCEPROP 1 LASTPIN (1875 4400) $PN 2
J 0
(1880 4410);
DISPLAY 0.787234 (1880 4410);
PAINT MONO (1880 4410);
FORCEPROP 2 LAST CDS_LIB pure_quanta
J 0
(1875 4500);
DISPLAY INVISIBLE (1875 4500);
FORCEPROP 1 LAST PATH I69
J 0
(1925 4675);
DISPLAY 0.978723 (1925 4675);
PAINT WHITE (1925 4675);
DISPLAY INVISIBLE (1925 4675);
FORCEPROP 0 LAST CDS_LOCATION R2973
J 0
(1925 4675);
DISPLAY 1.021277 (1925 4675);
DISPLAY INVISIBLE (1925 4675);
FORCEPROP 0 LAST $SEC 1
J 0
(1925 4675);
DISPLAY 0.680851 (1925 4675);
PAINT MONO (1925 4675);
DISPLAY INVISIBLE (1925 4675);
FORCEPROP 0 LAST CDS_SEC 1
J 0
(1925 4675);
DISPLAY 1.021277 (1925 4675);
DISPLAY INVISIBLE (1925 4675);
FORCEADD UNIVERSAL_POWER..1
R 2
(-1125 3275);
FORCEPROP 3 LASTPIN (-1125 3225) SIG_NAME P3V3_AUX\g
J 0
(-1115 3235);
DISPLAY 0.659574 (-1115 3235);
PAINT MONO (-1115 3235);
DISPLAY INVISIBLE (-1115 3235);
FORCEPROP 1 LAST HDL_POWER P3V3_AUX
J 1
(-1125 3325);
DISPLAY 0.723404 (-1125 3325);
PAINT GREEN (-1125 3325);
FORCEPROP 2 LAST CDS_LIB logical_power
J 0
(-1125 3275);
DISPLAY INVISIBLE (-1125 3275);
FORCEPROP 1 LAST PATH I7
J 2
(-1175 3300);
DISPLAY 0.872340 (-1175 3300);
PAINT AQUA (-1175 3300);
DISPLAY INVISIBLE (-1175 3300);
FORCEADD Q_RES..2
(2150 4500);
FORCEPROP 1 LAST PART_NUMBER CS21002FB06
J 0
(2190 4375);
DISPLAY 0.510638 (2190 4375);
DISPLAY INVISIBLE (2190 4375);
FORCEPROP 1 LAST PACK_TYPE 0402LF
J 0
(2190 4375);
DISPLAY 0.638298 (2190 4375);
FORCEPROP 1 LAST MATERIAL EMPTY
J 0
(2190 4425);
DISPLAY 0.638298 (2190 4425);
PAINT PINK (2190 4425);
FORCEPROP 1 LAST VALUE 1K
J 0
(2195 4575);
DISPLAY 0.638298 (2195 4575);
FORCEPROP 1 LAST TOLERANCE 1%
J 0
(2195 4525);
DISPLAY 0.638298 (2195 4525);
FORCEPROP 1 LAST WATTAGE 1/16W
J 0
(2190 4475);
DISPLAY 0.638298 (2190 4475);
FORCEPROP 1 LAST $LOCATION R2975
J 0
(2195 4625);
DISPLAY 0.978723 (2195 4625);
FORCEPROP 1 LASTPIN (2150 4600) $PN 1
J 0
(2155 4562);
DISPLAY 0.787234 (2155 4562);
PAINT MONO (2155 4562);
FORCEPROP 1 LASTPIN (2150 4400) $PN 2
J 0
(2155 4410);
DISPLAY 0.787234 (2155 4410);
PAINT MONO (2155 4410);
FORCEPROP 2 LAST CDS_LIB pure_quanta
J 0
(2150 4500);
DISPLAY INVISIBLE (2150 4500);
FORCEPROP 1 LAST PATH I70
J 0
(2200 4675);
DISPLAY 0.978723 (2200 4675);
PAINT WHITE (2200 4675);
DISPLAY INVISIBLE (2200 4675);
FORCEPROP 0 LAST CDS_LOCATION R2975
J 0
(2200 4675);
DISPLAY 1.021277 (2200 4675);
DISPLAY INVISIBLE (2200 4675);
FORCEPROP 0 LAST $SEC 1
J 0
(2200 4675);
DISPLAY 0.680851 (2200 4675);
PAINT MONO (2200 4675);
DISPLAY INVISIBLE (2200 4675);
FORCEPROP 0 LAST CDS_SEC 1
J 0
(2200 4675);
DISPLAY 1.021277 (2200 4675);
DISPLAY INVISIBLE (2200 4675);
FORCEADD Q_RES..2
(1875 5150);
FORCEPROP 1 LAST PART_NUMBER CS31002FB08
J 0
(1915 5025);
DISPLAY 0.510638 (1915 5025);
DISPLAY INVISIBLE (1915 5025);
FORCEPROP 1 LAST PACK_TYPE 0402LF
J 0
(1915 5025);
DISPLAY 0.638298 (1915 5025);
FORCEPROP 1 LAST MATERIAL CHIP
J 0
(1915 5075);
DISPLAY 0.638298 (1915 5075);
PAINT RED (1915 5075);
FORCEPROP 1 LAST WATTAGE 1/16W
J 0
(1915 5125);
DISPLAY 0.638298 (1915 5125);
FORCEPROP 1 LAST TOLERANCE 1%
J 0
(1920 5175);
DISPLAY 0.638298 (1920 5175);
FORCEPROP 1 LAST VALUE 10K
J 0
(1920 5225);
DISPLAY 0.638298 (1920 5225);
FORCEPROP 1 LAST $LOCATION R2972
J 0
(1920 5275);
DISPLAY 0.978723 (1920 5275);
FORCEPROP 1 LASTPIN (1875 5250) $PN 1
J 0
(1880 5212);
DISPLAY 0.787234 (1880 5212);
PAINT MONO (1880 5212);
FORCEPROP 1 LASTPIN (1875 5050) $PN 2
J 0
(1880 5060);
DISPLAY 0.787234 (1880 5060);
PAINT MONO (1880 5060);
FORCEPROP 2 LAST CDS_LIB pure_quanta
J 0
(1875 5150);
DISPLAY INVISIBLE (1875 5150);
FORCEPROP 1 LAST PATH I71
J 0
(1925 5325);
DISPLAY 0.978723 (1925 5325);
PAINT WHITE (1925 5325);
DISPLAY INVISIBLE (1925 5325);
FORCEPROP 0 LAST CDS_LOCATION R2972
J 0
(1925 5325);
DISPLAY 1.021277 (1925 5325);
DISPLAY INVISIBLE (1925 5325);
FORCEPROP 0 LAST $SEC 1
J 0
(1925 5325);
DISPLAY 0.680851 (1925 5325);
PAINT MONO (1925 5325);
DISPLAY INVISIBLE (1925 5325);
FORCEPROP 0 LAST CDS_SEC 1
J 0
(1925 5325);
DISPLAY 1.021277 (1925 5325);
DISPLAY INVISIBLE (1925 5325);
FORCEADD Q_RES..2
(2150 5150);
FORCEPROP 1 LAST PART_NUMBER CS31002FB08
J 0
(2190 5025);
DISPLAY 0.510638 (2190 5025);
DISPLAY INVISIBLE (2190 5025);
FORCEPROP 1 LAST PACK_TYPE 0402LF
J 0
(2190 5025);
DISPLAY 0.638298 (2190 5025);
FORCEPROP 1 LAST VALUE 10K
J 0
(2195 5225);
DISPLAY 0.638298 (2195 5225);
FORCEPROP 1 LAST TOLERANCE 1%
J 0
(2195 5175);
DISPLAY 0.638298 (2195 5175);
FORCEPROP 1 LAST WATTAGE 1/16W
J 0
(2190 5125);
DISPLAY 0.638298 (2190 5125);
FORCEPROP 1 LAST MATERIAL CHIP
J 0
(2190 5075);
DISPLAY 0.638298 (2190 5075);
PAINT RED (2190 5075);
FORCEPROP 1 LAST $LOCATION R2974
J 0
(2195 5275);
DISPLAY 0.978723 (2195 5275);
FORCEPROP 1 LASTPIN (2150 5250) $PN 1
J 0
(2155 5212);
DISPLAY 0.787234 (2155 5212);
PAINT MONO (2155 5212);
FORCEPROP 1 LASTPIN (2150 5050) $PN 2
J 0
(2155 5060);
DISPLAY 0.787234 (2155 5060);
PAINT MONO (2155 5060);
FORCEPROP 2 LAST CDS_LIB pure_quanta
J 0
(2150 5150);
DISPLAY INVISIBLE (2150 5150);
FORCEPROP 1 LAST PATH I72
J 0
(2200 5325);
DISPLAY 0.978723 (2200 5325);
PAINT WHITE (2200 5325);
DISPLAY INVISIBLE (2200 5325);
FORCEPROP 0 LAST CDS_LOCATION R2974
J 0
(2200 5325);
DISPLAY 1.021277 (2200 5325);
DISPLAY INVISIBLE (2200 5325);
FORCEPROP 0 LAST $SEC 1
J 0
(2200 5325);
DISPLAY 0.680851 (2200 5325);
PAINT MONO (2200 5325);
DISPLAY INVISIBLE (2200 5325);
FORCEPROP 0 LAST CDS_SEC 1
J 0
(2200 5325);
DISPLAY 1.021277 (2200 5325);
DISPLAY INVISIBLE (2200 5325);
FORCEADD UNIVERSAL_POWER..1
(1875 5525);
FORCEPROP 3 LASTPIN (1875 5475) SIG_NAME P1V05_PCH_AUX\g
J 0
(1885 5485);
DISPLAY 0.659574 (1885 5485);
PAINT MONO (1885 5485);
DISPLAY INVISIBLE (1885 5485);
FORCEPROP 1 LAST HDL_POWER P1V05_PCH_AUX
J 1
(1875 5575);
DISPLAY 0.872340 (1875 5575);
PAINT GREEN (1875 5575);
FORCEPROP 2 LAST CDS_LIB logical_power
J 0
(1875 5525);
PAINT MONO (1875 5525);
DISPLAY INVISIBLE (1875 5525);
FORCEPROP 1 LAST PATH I73
J 0
(1925 5550);
DISPLAY 0.872340 (1925 5550);
PAINT AQUA (1925 5550);
DISPLAY INVISIBLE (1925 5550);
FORCEADD Q_RES..2
(2425 4500);
FORCEPROP 1 LAST PART_NUMBER CS21002FB06
J 0
(2465 4375);
DISPLAY 0.510638 (2465 4375);
DISPLAY INVISIBLE (2465 4375);
FORCEPROP 1 LAST WATTAGE 1/16W
J 0
(2465 4475);
DISPLAY 0.638298 (2465 4475);
FORCEPROP 1 LAST VALUE 1K
J 0
(2470 4575);
DISPLAY 0.638298 (2470 4575);
FORCEPROP 1 LAST TOLERANCE 1%
J 0
(2470 4525);
DISPLAY 0.638298 (2470 4525);
FORCEPROP 1 LAST MATERIAL EMPTY
J 0
(2465 4425);
DISPLAY 0.638298 (2465 4425);
PAINT RED (2465 4425);
FORCEPROP 1 LAST PACK_TYPE 0402LF
J 0
(2465 4325);
DISPLAY 0.638298 (2465 4325);
FORCEPROP 1 LAST $LOCATION R2978
J 0
(2470 4625);
DISPLAY 0.978723 (2470 4625);
FORCEPROP 1 LASTPIN (2425 4600) $PN 1
J 0
(2430 4562);
DISPLAY 0.787234 (2430 4562);
PAINT MONO (2430 4562);
FORCEPROP 1 LASTPIN (2425 4400) $PN 2
J 0
(2430 4410);
DISPLAY 0.787234 (2430 4410);
PAINT MONO (2430 4410);
FORCEPROP 1 LAST PATH I74
J 0
(2475 4675);
DISPLAY 0.978723 (2475 4675);
PAINT WHITE (2475 4675);
DISPLAY INVISIBLE (2475 4675);
FORCEPROP 2 LAST CDS_LIB pure_quanta
J 0
(2425 4500);
DISPLAY INVISIBLE (2425 4500);
FORCEPROP 0 LAST CDS_LOCATION R2978
J 0
(2475 4675);
DISPLAY 1.021277 (2475 4675);
DISPLAY INVISIBLE (2475 4675);
FORCEPROP 0 LAST $SEC 1
J 0
(2475 4675);
DISPLAY 0.680851 (2475 4675);
PAINT MONO (2475 4675);
DISPLAY INVISIBLE (2475 4675);
FORCEPROP 0 LAST CDS_SEC 1
J 0
(2475 4675);
DISPLAY 1.021277 (2475 4675);
DISPLAY INVISIBLE (2475 4675);
FORCEADD Q_RES..2
(2425 5150);
FORCEPROP 1 LAST PART_NUMBER CS31002FB08
J 0
(2465 5025);
DISPLAY 0.510638 (2465 5025);
DISPLAY INVISIBLE (2465 5025);
FORCEPROP 1 LAST PACK_TYPE 0402LF
J 0
(2465 4975);
DISPLAY 0.638298 (2465 4975);
FORCEPROP 1 LAST TOLERANCE 1%
J 0
(2470 5175);
DISPLAY 0.638298 (2470 5175);
FORCEPROP 1 LAST VALUE 10K
J 0
(2470 5225);
DISPLAY 0.638298 (2470 5225);
FORCEPROP 1 LAST WATTAGE 1/16W
J 0
(2465 5125);
DISPLAY 0.638298 (2465 5125);
FORCEPROP 1 LAST MATERIAL CHIP
J 0
(2465 5075);
DISPLAY 0.638298 (2465 5075);
PAINT SALMON (2465 5075);
FORCEPROP 1 LAST $LOCATION R2232
J 0
(2470 5275);
DISPLAY 0.978723 (2470 5275);
FORCEPROP 1 LASTPIN (2425 5250) $PN 1
J 0
(2430 5212);
DISPLAY 0.787234 (2430 5212);
PAINT MONO (2430 5212);
FORCEPROP 1 LASTPIN (2425 5050) $PN 2
J 0
(2430 5060);
DISPLAY 0.787234 (2430 5060);
PAINT MONO (2430 5060);
FORCEPROP 1 LAST PATH I75
J 0
(2475 5325);
DISPLAY 0.978723 (2475 5325);
PAINT WHITE (2475 5325);
DISPLAY INVISIBLE (2475 5325);
FORCEPROP 2 LAST CDS_LIB pure_quanta
J 0
(2425 5150);
DISPLAY INVISIBLE (2425 5150);
FORCEPROP 0 LAST CDS_LOCATION R2232
J 0
(2475 5325);
DISPLAY 1.021277 (2475 5325);
DISPLAY INVISIBLE (2475 5325);
FORCEPROP 0 LAST $SEC 1
J 0
(2475 5325);
DISPLAY 0.680851 (2475 5325);
PAINT MONO (2475 5325);
DISPLAY INVISIBLE (2475 5325);
FORCEPROP 0 LAST CDS_SEC 1
J 0
(2475 5325);
DISPLAY 1.021277 (2475 5325);
DISPLAY INVISIBLE (2475 5325);
FORCEADD OFFPAGE..2
(3550 2250);
FORCEPROP 2 LAST $XR0 216 
J 0
(3739 2250);
DISPLAY 0.638298 (3739 2250);
PAINT MONO (3739 2250);
FORCEPROP 1 LAST COMMENT_BODY TRUE
J 0
(3505 2155);
DISPLAY 0.872340 (3505 2155);
PAINT GREEN (3505 2155);
DISPLAY INVISIBLE (3505 2155);
FORCEPROP 1 LAST OFFPAGE TRUE
J 0
(3875 2125);
DISPLAY 0.872340 (3875 2125);
DISPLAY INVISIBLE (3875 2125);
FORCEPROP 2 LAST CDS_LIB standard
J 0
(3550 2250);
PAINT MONO (3550 2250);
DISPLAY INVISIBLE (3550 2250);
FORCEPROP 2 LAST PATH I76
J 0
(3750 2300);
DISPLAY 1.021277 (3750 2300);
DISPLAY INVISIBLE (3750 2300);
FORCEADD OFFPAGE..2
(3550 2325);
FORCEPROP 2 LAST $XR0 216 
J 0
(3739 2325);
DISPLAY 0.638298 (3739 2325);
PAINT MONO (3739 2325);
FORCEPROP 1 LAST COMMENT_BODY TRUE
J 0
(3505 2230);
DISPLAY 0.872340 (3505 2230);
PAINT GREEN (3505 2230);
DISPLAY INVISIBLE (3505 2230);
FORCEPROP 1 LAST OFFPAGE TRUE
J 0
(3875 2200);
DISPLAY 0.872340 (3875 2200);
DISPLAY INVISIBLE (3875 2200);
FORCEPROP 2 LAST CDS_LIB standard
J 0
(3550 2325);
PAINT MONO (3550 2325);
DISPLAY INVISIBLE (3550 2325);
FORCEPROP 2 LAST PATH I77
J 0
(3750 2375);
DISPLAY 1.021277 (3750 2375);
DISPLAY INVISIBLE (3750 2375);
FORCEADD OFFPAGE..2
(3550 2400);
FORCEPROP 2 LAST $XR0 216 
J 0
(3739 2400);
DISPLAY 0.638298 (3739 2400);
PAINT MONO (3739 2400);
FORCEPROP 1 LAST COMMENT_BODY TRUE
J 0
(3505 2305);
DISPLAY 0.872340 (3505 2305);
PAINT GREEN (3505 2305);
DISPLAY INVISIBLE (3505 2305);
FORCEPROP 1 LAST OFFPAGE TRUE
J 0
(3875 2275);
DISPLAY 0.872340 (3875 2275);
DISPLAY INVISIBLE (3875 2275);
FORCEPROP 2 LAST CDS_LIB standard
J 0
(3550 2400);
PAINT MONO (3550 2400);
DISPLAY INVISIBLE (3550 2400);
FORCEPROP 2 LAST PATH I78
J 0
(3750 2450);
DISPLAY 1.021277 (3750 2450);
DISPLAY INVISIBLE (3750 2450);
FORCEADD OFFPAGE..2
(3550 4725);
FORCEPROP 2 LAST $XR0 184 
J 0
(3739 4725);
DISPLAY 0.638298 (3739 4725);
PAINT MONO (3739 4725);
FORCEPROP 1 LAST COMMENT_BODY TRUE
J 0
(3505 4630);
DISPLAY 0.872340 (3505 4630);
PAINT GREEN (3505 4630);
DISPLAY INVISIBLE (3505 4630);
FORCEPROP 1 LAST OFFPAGE TRUE
J 0
(3875 4600);
DISPLAY 0.872340 (3875 4600);
DISPLAY INVISIBLE (3875 4600);
FORCEPROP 2 LAST CDS_LIB standard
J 0
(3550 4725);
PAINT MONO (3550 4725);
DISPLAY INVISIBLE (3550 4725);
FORCEPROP 2 LAST PATH I79
J 0
(3750 4775);
DISPLAY 1.021277 (3750 4775);
DISPLAY INVISIBLE (3750 4775);
FORCEADD UNIVERSAL_GND..1
(-1225 4175);
FORCEPROP 3 LASTPIN (-1225 4225) SIG_NAME GND\g
J 0
(-1215 4235);
DISPLAY 0.659574 (-1215 4235);
PAINT MONO (-1215 4235);
DISPLAY INVISIBLE (-1215 4235);
FORCEPROP 1 LAST HDL_POWER GND
J 1
(-1200 4100);
DISPLAY 0.872340 (-1200 4100);
PAINT GREEN (-1200 4100);
DISPLAY INVISIBLE (-1200 4100);
FORCEPROP 2 LAST CDS_LIB logical_power
J 0
(-1225 4175);
PAINT MONO (-1225 4175);
DISPLAY INVISIBLE (-1225 4175);
FORCEPROP 1 LAST PATH I8
J 0
(-1150 4175);
DISPLAY 0.872340 (-1150 4175);
PAINT AQUA (-1150 4175);
DISPLAY INVISIBLE (-1150 4175);
FORCEADD OFFPAGE..2
(3550 4800);
FORCEPROP 2 LAST $XR0 184 
J 0
(3739 4800);
DISPLAY 0.638298 (3739 4800);
PAINT MONO (3739 4800);
FORCEPROP 1 LAST COMMENT_BODY TRUE
J 0
(3505 4705);
DISPLAY 0.872340 (3505 4705);
PAINT GREEN (3505 4705);
DISPLAY INVISIBLE (3505 4705);
FORCEPROP 1 LAST OFFPAGE TRUE
J 0
(3875 4675);
DISPLAY 0.872340 (3875 4675);
DISPLAY INVISIBLE (3875 4675);
FORCEPROP 2 LAST CDS_LIB standard
J 0
(3550 4800);
PAINT MONO (3550 4800);
DISPLAY INVISIBLE (3550 4800);
FORCEPROP 2 LAST PATH I80
J 0
(3750 4850);
DISPLAY 1.021277 (3750 4850);
DISPLAY INVISIBLE (3750 4850);
FORCEADD OFFPAGE..2
(3550 4875);
FORCEPROP 2 LAST $XR0 184 
J 0
(3739 4875);
DISPLAY 0.638298 (3739 4875);
PAINT MONO (3739 4875);
FORCEPROP 1 LAST COMMENT_BODY TRUE
J 0
(3505 4780);
DISPLAY 0.872340 (3505 4780);
PAINT GREEN (3505 4780);
DISPLAY INVISIBLE (3505 4780);
FORCEPROP 1 LAST OFFPAGE TRUE
J 0
(3875 4750);
DISPLAY 0.872340 (3875 4750);
DISPLAY INVISIBLE (3875 4750);
FORCEPROP 2 LAST CDS_LIB standard
J 0
(3550 4875);
PAINT MONO (3550 4875);
DISPLAY INVISIBLE (3550 4875);
FORCEPROP 2 LAST PATH I81
J 0
(3750 4925);
DISPLAY 1.021277 (3750 4925);
DISPLAY INVISIBLE (3750 4925);
FORCEADD Q_RES..2
(-1225 4400);
FORCEPROP 1 LAST PART_NUMBER CS21002FB06
J 0
(-1185 4275);
DISPLAY 0.510638 (-1185 4275);
DISPLAY INVISIBLE (-1185 4275);
FORCEPROP 1 LAST PACK_TYPE 0402LF
J 0
(-1185 4275);
DISPLAY 0.638298 (-1185 4275);
FORCEPROP 1 LAST MATERIAL CHIP
J 0
(-1185 4325);
DISPLAY 0.638298 (-1185 4325);
FORCEPROP 1 LAST WATTAGE 1/16W
J 0
(-1185 4375);
DISPLAY 0.638298 (-1185 4375);
FORCEPROP 1 LAST TOLERANCE 1%
J 0
(-1180 4425);
DISPLAY 0.638298 (-1180 4425);
FORCEPROP 1 LAST VALUE 1K
J 0
(-1180 4475);
DISPLAY 0.638298 (-1180 4475);
FORCEPROP 1 LAST $LOCATION R2235
J 0
(-1180 4525);
DISPLAY 0.978723 (-1180 4525);
FORCEPROP 1 LASTPIN (-1225 4500) $PN 1
J 0
(-1220 4462);
DISPLAY 0.787234 (-1220 4462);
PAINT MONO (-1220 4462);
FORCEPROP 1 LASTPIN (-1225 4300) $PN 2
J 0
(-1220 4310);
DISPLAY 0.787234 (-1220 4310);
PAINT MONO (-1220 4310);
FORCEPROP 2 LAST CDS_LIB pure_quanta
J 0
(-1225 4400);
DISPLAY INVISIBLE (-1225 4400);
FORCEPROP 1 LAST PATH I9
J 0
(-1175 4575);
DISPLAY 0.978723 (-1175 4575);
PAINT WHITE (-1175 4575);
DISPLAY INVISIBLE (-1175 4575);
FORCEPROP 0 LAST CDS_LOCATION R2235
J 0
(-1175 4575);
DISPLAY 1.021277 (-1175 4575);
DISPLAY INVISIBLE (-1175 4575);
FORCEPROP 0 LAST $SEC 1
J 0
(-1175 4575);
DISPLAY 0.680851 (-1175 4575);
PAINT MONO (-1175 4575);
DISPLAY INVISIBLE (-1175 4575);
FORCEPROP 0 LAST CDS_SEC 1
J 0
(-1175 4575);
DISPLAY 1.021277 (-1175 4575);
DISPLAY INVISIBLE (-1175 4575);
FORCEADD QUANTA_TITLE_BLOCK_C..1
(4300 -650);
FORCEPROP 0 LAST CDS_CON_LAST_MODIFIED Fri Aug 25 14:03:09 2023
J 0
(2415 -635);
PAINT MONO (2415 -635);
DISPLAY INVISIBLE (2415 -635);
FORCEPROP 2 LAST CUSTOM_TXT_CDS <XR_PAGE_TITLE>
J 0
(-3590 4600);
DISPLAY 0.638298 (-3590 4600);
PAINT PINK (-3590 4600);
DISPLAY INVISIBLE (-3590 4600);
FORCEPROP 2 LAST CUSTOM_TXT_CDS <CON_LAST_MODIFIED>
J 0
(2415 -635);
DISPLAY 0.978723 (2415 -635);
FORCEPROP 2 LAST CUSTOM_TXT_CDS <Q_PROJ>
J 0
(1918 -548);
DISPLAY 1.212766 (1918 -548);
FORCEPROP 2 LAST CUSTOM_TXT_CDS <Q_REV>
J 0
(4116 -547);
DISPLAY 1.212766 (4116 -547);
FORCEPROP 2 LAST CUSTOM_TXT_CDS <NAME_1>
J 0
(1125 -475);
FORCEPROP 2 LAST CUSTOM_TXT_CDS <NAME_2>
J 0
(1125 -600);
FORCEPROP 2 LAST CUSTOM_TXT_CDS <Q_NUMBER>
J 0
(2897 -547);
DISPLAY 1.212766 (2897 -547);
FORCEPROP 2 LAST CUSTOM_TXT_CDS <CON_PAGE_NUM> OF <CON_TOTAL_PAGES>
J 0
(3854 -632);
DISPLAY 0.978723 (3854 -632);
FORCEPROP 1 LAST Q_TITLE BOARD IDS
J 0
(-5041 -624);
DISPLAY 1.957447 (-5041 -624);
PAINT GREEN (-5041 -624);
FORCEPROP 1 LAST Q_DEPT 
J 1
(537 -601);
DISPLAY 1.957447 (537 -601);
PAINT GREEN (537 -601);
FORCEPROP 1 LAST COMMENT_BODY TRUE
J 0
(4312 -663);
DISPLAY 0.978723 (4312 -663);
PAINT GREEN (4312 -663);
DISPLAY INVISIBLE (4312 -663);
FORCEPROP 2 LAST CDS_LIB pure_quanta
J 0
(4300 -650);
PAINT MONO (4300 -650);
DISPLAY INVISIBLE (4300 -650);
FORCEPROP 1 LAST CDS_LMAN_SYM_OUTLINE -9475,6775,100,-125
J 0
(4300 -650);
DISPLAY 0.468085 (4300 -650);
PAINT GREEN (4300 -650);
DISPLAY INVISIBLE (4300 -650);
FORCEPROP 2 LAST PAGE_BORDER TRUE
J 0
(-3590 4600);
DISPLAY 0.638298 (-3590 4600);
PAINT PINK (-3590 4600);
DISPLAY INVISIBLE (-3590 4600);
FORCEPROP 2 LAST CDS_XR_PAGE_TITLE CR-195 : @S9S_MB_2U_LIB.S9S_MB_2U(SCH_1):PAGE195
J 0
(-3590 4600);
DISPLAY 0.638298 (-3590 4600);
PAINT PINK (-3590 4600);
DISPLAY INVISIBLE (-3590 4600);
FORCEADD DNS..2
(2425 4475);
PAINT RED (2425 4475);
FORCEPROP 2 LAST CDS_LIB mstr_misc
J 0
(2425 4475);
PAINT MONO (2425 4475);
DISPLAY INVISIBLE (2425 4475);
FORCEPROP 1 LAST COMMENT_BODY TRUE
J 0
(2425 4475);
DISPLAY INVISIBLE (2425 4475);
FORCEADD DNS..2
(2425 2000);
PAINT RED (2425 2000);
FORCEPROP 1 LAST COMMENT_BODY TRUE
J 0
(2425 2000);
DISPLAY INVISIBLE (2425 2000);
FORCEPROP 2 LAST CDS_LIB mstr_misc
J 0
(2425 2000);
DISPLAY INVISIBLE (2425 2000);
FORCEADD DESIGN_NOTE..1
(2300 1150);
FORCEPROP 1 LAST COMMENT_BODY TRUE
J 0
(2325 1250);
DISPLAY 0.978723 (2325 1250);
DISPLAY INVISIBLE (2325 1250);
FORCEPROP 2 LAST CDS_LIB logical_power
J 0
(2300 1150);
DISPLAY INVISIBLE (2300 1150);
FORCEADD DNS..2
(1875 2000);
PAINT RED (1875 2000);
FORCEPROP 2 LAST CDS_LIB mstr_misc
J 0
(1875 2000);
PAINT MONO (1875 2000);
DISPLAY INVISIBLE (1875 2000);
FORCEPROP 1 LAST COMMENT_BODY TRUE
J 0
(1875 2000);
DISPLAY INVISIBLE (1875 2000);
FORCEADD DNS..2
(2150 2000);
PAINT RED (2150 2000);
FORCEPROP 2 LAST CDS_LIB mstr_misc
J 0
(2150 2000);
DISPLAY INVISIBLE (2150 2000);
FORCEPROP 1 LAST COMMENT_BODY TRUE
J 0
(2150 2000);
DISPLAY INVISIBLE (2150 2000);
FORCEADD DNS..2
(1875 4475);
PAINT RED (1875 4475);
FORCEPROP 1 LAST COMMENT_BODY TRUE
J 0
(1875 4475);
DISPLAY INVISIBLE (1875 4475);
FORCEPROP 2 LAST CDS_LIB mstr_misc
J 0
(1875 4475);
PAINT MONO (1875 4475);
DISPLAY INVISIBLE (1875 4475);
FORCEADD DNS..2
(2150 4475);
PAINT RED (2150 4475);
FORCEPROP 2 LAST CDS_LIB mstr_misc
J 0
(2150 4475);
DISPLAY INVISIBLE (2150 4475);
FORCEPROP 1 LAST COMMENT_BODY TRUE
J 0
(2150 4475);
DISPLAY INVISIBLE (2150 4475);
FORCEADD DNS..2
(-1120 2870);
PAINT RED (-1120 2870);
FORCEPROP 2 LAST CDS_LIB mstr_misc
J 0
(-1120 2870);
PAINT MONO (-1120 2870);
DISPLAY INVISIBLE (-1120 2870);
FORCEPROP 1 LAST COMMENT_BODY TRUE
J 0
(-1120 2870);
DISPLAY INVISIBLE (-1120 2870);
FORCEADD DNS..2
(-845 2870);
PAINT RED (-845 2870);
FORCEPROP 2 LAST CDS_LIB mstr_misc
J 0
(-845 2870);
DISPLAY INVISIBLE (-845 2870);
FORCEPROP 1 LAST COMMENT_BODY TRUE
J 0
(-845 2870);
DISPLAY INVISIBLE (-845 2870);
FORCEADD DESIGN_NOTE..1
(-4250 5025);
FORCEPROP 1 LAST COMMENT_BODY TRUE
J 0
(-4225 5125);
DISPLAY 0.978723 (-4225 5125);
DISPLAY INVISIBLE (-4225 5125);
FORCEPROP 2 LAST CDS_LIB logical_power
J 0
(-4250 5025);
DISPLAY INVISIBLE (-4250 5025);
FORCEADD DNS..2
(-1220 5195);
PAINT RED (-1220 5195);
FORCEPROP 2 LAST CDS_LIB mstr_misc
J 0
(-1220 5195);
PAINT MONO (-1220 5195);
DISPLAY INVISIBLE (-1220 5195);
FORCEPROP 1 LAST COMMENT_BODY TRUE
J 0
(-1220 5195);
DISPLAY INVISIBLE (-1220 5195);
FORCEADD DNS..2
(-945 5195);
PAINT RED (-945 5195);
FORCEPROP 2 LAST CDS_LIB mstr_misc
J 0
(-945 5195);
DISPLAY INVISIBLE (-945 5195);
FORCEPROP 1 LAST COMMENT_BODY TRUE
J 0
(-945 5195);
DISPLAY INVISIBLE (-945 5195);
FORCEADD DNS..2
(-670 5195);
PAINT RED (-670 5195);
FORCEPROP 2 LAST CDS_LIB mstr_misc
J 0
(-670 5195);
DISPLAY INVISIBLE (-670 5195);
FORCEPROP 1 LAST COMMENT_BODY TRUE
J 0
(-670 5195);
DISPLAY INVISIBLE (-670 5195);
FORCEADD DNS..2
(-570 2870);
PAINT RED (-570 2870);
FORCEPROP 2 LAST CDS_LIB mstr_misc
J 0
(-570 2870);
DISPLAY INVISIBLE (-570 2870);
FORCEPROP 1 LAST COMMENT_BODY TRUE
J 0
(-570 2870);
DISPLAY INVISIBLE (-570 2870);
FORCEADD DNS..2
(-295 2870);
PAINT RED (-295 2870);
FORCEPROP 2 LAST CDS_LIB mstr_misc
J 0
(-295 2870);
DISPLAY INVISIBLE (-295 2870);
FORCEPROP 1 LAST COMMENT_BODY TRUE
J 0
(-295 2870);
DISPLAY INVISIBLE (-295 2870);
FORCEADD DNS..2
(-25 2875);
PAINT RED (-25 2875);
FORCEPROP 1 LAST COMMENT_BODY TRUE
J 0
(-25 2875);
DISPLAY INVISIBLE (-25 2875);
FORCEPROP 2 LAST CDS_LIB mstr_misc
J 0
(-25 2875);
DISPLAY INVISIBLE (-25 2875);
FORCEADD DNS..2
(-395 5195);
PAINT RED (-395 5195);
FORCEPROP 2 LAST CDS_LIB mstr_misc
J 0
(-395 5195);
DISPLAY INVISIBLE (-395 5195);
FORCEPROP 1 LAST COMMENT_BODY TRUE
J 0
(-395 5195);
DISPLAY INVISIBLE (-395 5195);
FORCEADD DNS..2
(-120 5195);
PAINT RED (-120 5195);
FORCEPROP 2 LAST CDS_LIB mstr_misc
J 0
(-120 5195);
PAINT MONO (-120 5195);
DISPLAY INVISIBLE (-120 5195);
FORCEPROP 1 LAST COMMENT_BODY TRUE
J 0
(-120 5195);
DISPLAY INVISIBLE (-120 5195);
WIRE 16 -1 (1875 2925)(1875 3000);
WIRE 16 -1 (1875 2925)(2150 2925);
WIRE 16 -1 (1875 2775)(1875 2925);
WIRE 16 -1 (1875 5400)(1875 5475);
WIRE 16 -1 (1875 5400)(2150 5400);
WIRE 16 -1 (1875 5250)(1875 5400);
WIRE 16 -1 (-1125 3150)(-1125 3225);
WIRE 16 -1 (-1125 3150)(-850 3150);
WIRE 16 -1 (-1125 3000)(-1125 3150);
WIRE 16 -1 (-1225 5475)(-1225 5550);
WIRE 16 -1 (-1225 5475)(-950 5475);
WIRE 16 -1 (-1225 5325)(-1225 5475);
WIRE 16 -1 (2150 1850)(2150 1925);
WIRE 16 -1 (1875 1850)(1875 1925);
WIRE 16 -1 (2425 1850)(2425 1925);
WIRE 16 -1 (1875 4325)(1875 4400);
WIRE 16 -1 (2150 4325)(2150 4400);
WIRE 16 -1 (2425 4325)(2425 4400);
WIRE 16 -1 (-1125 1900)(-1125 1975);
WIRE 16 -1 (-850 1900)(-850 1975);
WIRE 16 -1 (-1225 4225)(-1225 4300);
WIRE 16 -1 (-950 4225)(-950 4300);
WIRE 16 -1 (-575 1900)(-575 1975);
WIRE 16 -1 (-300 1900)(-300 1975);
WIRE 16 -1 (-25 1900)(-25 1975);
WIRE 16 -1 (-675 4225)(-675 4300);
WIRE 16 -1 (-400 4225)(-400 4300);
WIRE 16 -1 (-125 4225)(-125 4300);
WIRE 16 2175 (1625 1700)(3900 1700);
WIRE 16 2175 (3900 3150)(3900 1700);
WIRE 16 2175 (1625 3150)(1625 1700);
WIRE 16 2175 (1625 3150)(3900 3150);
WIRE 16 2175 (-1450 3500)(1400 3500);
WIRE 16 2175 (1400 3500)(1400 1675);
WIRE 16 2175 (-1450 3500)(-1450 1675);
WIRE 16 2175 (-1450 1675)(1400 1675);
WIRE 16 -1 (1875 4875)(1875 4600);
WIRE 16 -1 (1875 5050)(1875 4875);
WIRE 16 -1 (1875 4875)(3500 4875);
FORCEPROP 2 LAST SIG_NAME FAB_REV_ID2
J 0
(2690 4885);
DISPLAY 0.808511 (2690 4885);
PAINT WHITE (2690 4885);
WIRE 16 -1 (2150 4800)(2150 4600);
WIRE 16 -1 (2150 5050)(2150 4800);
WIRE 16 -1 (2150 4800)(3500 4800);
FORCEPROP 2 LAST SIG_NAME FAB_REV_ID1
J 0
(2690 4810);
DISPLAY 0.808511 (2690 4810);
PAINT WHITE (2690 4810);
WIRE 16 -1 (2425 4725)(2425 4600);
WIRE 16 -1 (2425 5050)(2425 4725);
WIRE 16 -1 (2425 4725)(3500 4725);
FORCEPROP 2 LAST SIG_NAME FAB_REV_ID0
J 0
(2690 4735);
DISPLAY 0.808511 (2690 4735);
PAINT WHITE (2690 4735);
WIRE 16 -1 (1875 2400)(1875 2125);
WIRE 16 -1 (1875 2575)(1875 2400);
WIRE 16 -1 (1875 2400)(3500 2400);
FORCEPROP 2 LAST SIG_NAME FAB_BMC_REV_ID2
J 0
(2690 2410);
DISPLAY 0.808511 (2690 2410);
PAINT WHITE (2690 2410);
WIRE 16 -1 (2425 2250)(2425 2125);
WIRE 16 -1 (2425 2575)(2425 2250);
WIRE 16 -1 (2425 2250)(3500 2250);
FORCEPROP 2 LAST SIG_NAME FAB_BMC_REV_ID0
J 0
(2690 2260);
DISPLAY 0.808511 (2690 2260);
PAINT WHITE (2690 2260);
WIRE 16 -1 (2100 -100)(2575 -100);
WIRE 16 -1 (2100 -100)(2100 25);
WIRE 16 -1 (2100 25)(2100 150);
WIRE 16 -1 (2575 25)(2575 -100);
WIRE 16 -1 (2100 25)(2575 25);
WIRE 16 -1 (2575 -100)(2975 -100);
WIRE 16 -1 (2975 -100)(3400 -100);
WIRE 16 -1 (2975 25)(2975 -100);
WIRE 16 -1 (2575 25)(2975 25);
WIRE 16 -1 (2100 150)(2575 150);
WIRE 16 -1 (2575 150)(2575 25);
WIRE 16 -1 (2100 150)(2100 275);
WIRE 16 -1 (2100 275)(2100 400);
WIRE 16 -1 (2100 275)(2575 275);
WIRE 16 -1 (2575 275)(2575 150);
WIRE 16 -1 (2575 150)(2975 150);
WIRE 16 -1 (2975 150)(2975 25);
WIRE 16 -1 (3400 25)(3400 -100);
WIRE 16 -1 (2975 25)(3400 25);
WIRE 16 -1 (3400 -100)(3825 -100);
WIRE 16 -1 (3825 -100)(3825 25);
WIRE 16 -1 (3400 25)(3825 25);
WIRE 16 -1 (2975 150)(3400 150);
WIRE 16 -1 (3400 150)(3400 25);
WIRE 16 -1 (2575 275)(2975 275);
WIRE 16 -1 (2975 275)(2975 150);
WIRE 16 -1 (2100 400)(2575 400);
WIRE 16 -1 (2575 400)(2575 275);
WIRE 16 -1 (2100 400)(2100 525);
WIRE 16 -1 (2100 650)(2100 525);
WIRE 16 -1 (2100 525)(2575 525);
WIRE 16 -1 (2575 525)(2575 400);
WIRE 16 -1 (2575 400)(2975 400);
WIRE 16 -1 (2975 400)(2975 275);
WIRE 16 -1 (3400 150)(3825 150);
WIRE 16 -1 (3825 25)(3825 150);
WIRE 16 -1 (2975 275)(3400 275);
WIRE 16 -1 (3400 275)(3400 150);
WIRE 16 -1 (3400 275)(3825 275);
WIRE 16 -1 (3825 150)(3825 275);
WIRE 16 -1 (2975 400)(3400 400);
WIRE 16 -1 (3400 400)(3400 275);
WIRE 16 -1 (2975 525)(2975 400);
WIRE 16 -1 (2575 525)(2975 525);
WIRE 16 -1 (2100 650)(2575 650);
WIRE 16 -1 (2575 525)(2575 650);
WIRE 16 -1 (2100 775)(2100 650);
WIRE 16 -1 (2100 900)(2100 775);
WIRE 16 -1 (2100 1025)(2100 900);
WIRE 16 -1 (2100 775)(2575 775);
WIRE 16 -1 (2575 775)(2575 650);
WIRE 16 -1 (2575 650)(2975 650);
WIRE 16 -1 (2975 650)(2975 525);
WIRE 16 -1 (3400 400)(3825 400);
WIRE 16 -1 (3825 275)(3825 400);
WIRE 16 -1 (2975 525)(3400 525);
WIRE 16 -1 (3400 525)(3400 400);
WIRE 16 -1 (3400 525)(3825 525);
WIRE 16 -1 (3825 400)(3825 525);
WIRE 16 -1 (2975 650)(3400 650);
WIRE 16 -1 (3400 650)(3400 525);
WIRE 16 -1 (2575 775)(2975 775);
WIRE 16 -1 (2975 775)(2975 650);
WIRE 16 -1 (2100 900)(2575 900);
WIRE 16 -1 (2575 775)(2575 900);
WIRE 16 -1 (2575 1025)(2100 1025);
WIRE 16 -1 (2575 900)(2575 1025);
WIRE 16 -1 (2975 1025)(2575 1025);
WIRE 16 -1 (2575 900)(2975 900);
WIRE 16 -1 (2975 900)(2975 775);
WIRE 16 -1 (2975 1025)(2975 900);
WIRE 16 -1 (3400 650)(3825 650);
WIRE 16 -1 (3825 525)(3825 650);
WIRE 16 -1 (2975 775)(3400 775);
WIRE 16 -1 (3400 775)(3400 650);
WIRE 16 -1 (3400 775)(3825 775);
WIRE 16 -1 (3825 775)(3825 650);
WIRE 16 -1 (2975 900)(3400 900);
WIRE 16 -1 (3400 900)(3400 775);
WIRE 16 -1 (3400 1025)(2975 1025);
WIRE 16 -1 (3400 1025)(3400 900);
WIRE 16 -1 (3825 1025)(3400 1025);
WIRE 16 -1 (3400 900)(3825 900);
WIRE 16 -1 (3825 775)(3825 900);
WIRE 16 -1 (3825 900)(3825 1025);
WIRE 16 -1 (2150 2775)(2150 2925);
WIRE 16 -1 (2150 2925)(2425 2925);
WIRE 16 -1 (2425 2775)(2425 2925);
WIRE 16 -1 (2150 2325)(2150 2125);
WIRE 16 -1 (2150 2575)(2150 2325);
WIRE 16 -1 (2150 2325)(3500 2325);
FORCEPROP 2 LAST SIG_NAME FAB_BMC_REV_ID1
J 0
(2690 2335);
DISPLAY 0.808511 (2690 2335);
PAINT WHITE (2690 2335);
WIRE 16 -1 (2150 5250)(2150 5400);
WIRE 16 -1 (2150 5400)(2425 5400);
WIRE 16 -1 (2425 5250)(2425 5400);
WIRE 16 -1 (-850 3000)(-850 3150);
WIRE 16 -1 (-575 3000)(-575 3150);
WIRE 16 -1 (-850 3150)(-575 3150);
WIRE 16 -1 (-300 3000)(-300 3150);
WIRE 16 -1 (-575 3150)(-300 3150);
WIRE 16 -1 (-300 3150)(-25 3150);
WIRE 16 -1 (-25 3000)(-25 3150);
WIRE 74 -1 (-2800 4100)(-4550 4100);
WIRE 74 -1 (-4550 3975)(-4550 4100);
WIRE 74 -1 (-4550 3975)(-4550 3850);
WIRE 74 -1 (-4550 3975)(-2800 3975);
WIRE 74 -1 (-2800 4100)(-2800 3975);
WIRE 74 -1 (-2500 4100)(-2800 4100);
WIRE 74 -1 (-2225 4100)(-2500 4100);
WIRE 74 -1 (-2800 3975)(-2500 3975);
WIRE 74 -1 (-2500 4100)(-2500 3975);
WIRE 74 -1 (-4550 3850)(-2800 3850);
WIRE 74 -1 (-2800 3975)(-2800 3850);
WIRE 74 -1 (-4550 3725)(-4550 3850);
WIRE 74 -1 (-4550 3600)(-4550 3725);
WIRE 74 -1 (-4550 3725)(-2800 3725);
WIRE 74 -1 (-2800 3850)(-2800 3725);
WIRE 74 -1 (-2800 3850)(-2500 3850);
WIRE 74 -1 (-2500 3975)(-2500 3850);
WIRE 74 -1 (-2500 3975)(-2225 3975);
WIRE 74 -1 (-2225 4100)(-2225 3975);
WIRE 74 -1 (-1925 4100)(-2225 4100);
WIRE 74 -1 (-1625 4100)(-1925 4100);
WIRE 74 -1 (-2225 3975)(-1925 3975);
WIRE 74 -1 (-1925 4100)(-1925 3975);
WIRE 74 -1 (-2500 3850)(-2225 3850);
WIRE 74 -1 (-2225 3975)(-2225 3850);
WIRE 74 -1 (-2800 3725)(-2500 3725);
WIRE 74 -1 (-2500 3850)(-2500 3725);
WIRE 74 -1 (-4550 3600)(-2800 3600);
WIRE 74 -1 (-2800 3725)(-2800 3600);
WIRE 74 -1 (-4550 3475)(-4550 3600);
WIRE 74 -1 (-4550 3475)(-4550 3350);
WIRE 74 -1 (-4550 3475)(-2800 3475);
WIRE 74 -1 (-2800 3600)(-2800 3475);
WIRE 74 -1 (-2800 3600)(-2500 3600);
WIRE 74 -1 (-2500 3725)(-2500 3600);
WIRE 74 -1 (-2500 3725)(-2225 3725);
WIRE 74 -1 (-2225 3850)(-2225 3725);
WIRE 74 -1 (-1925 3975)(-1625 3975);
WIRE 74 -1 (-1625 4100)(-1625 3975);
WIRE 74 -1 (-2225 3850)(-1925 3850);
WIRE 74 -1 (-1925 3975)(-1925 3850);
WIRE 74 -1 (-1925 3850)(-1625 3850);
WIRE 74 -1 (-1625 3975)(-1625 3850);
WIRE 74 -1 (-2225 3725)(-1925 3725);
WIRE 74 -1 (-1925 3850)(-1925 3725);
WIRE 74 -1 (-2500 3600)(-2225 3600);
WIRE 74 -1 (-2225 3725)(-2225 3600);
WIRE 74 -1 (-2800 3475)(-2500 3475);
WIRE 74 -1 (-2500 3600)(-2500 3475);
WIRE 74 -1 (-4550 3350)(-2800 3350);
WIRE 74 -1 (-2800 3475)(-2800 3350);
WIRE 74 -1 (-4550 3225)(-4550 3350);
WIRE 74 -1 (-4550 2475)(-2800 2475);
WIRE 74 -1 (-4550 2475)(-4550 2600);
WIRE 74 -1 (-4550 2600)(-4550 2725);
WIRE 74 -1 (-4550 2600)(-2800 2600);
WIRE 74 -1 (-2800 2600)(-2800 2475);
WIRE 74 -1 (-2800 2475)(-2500 2475);
WIRE 74 -1 (-4550 3100)(-4550 3225);
WIRE 74 -1 (-4550 3225)(-2800 3225);
WIRE 74 -1 (-2800 3350)(-2800 3225);
WIRE 74 -1 (-2800 3350)(-2500 3350);
WIRE 74 -1 (-2500 3475)(-2500 3350);
WIRE 74 -1 (-2500 3475)(-2225 3475);
WIRE 74 -1 (-2225 3600)(-2225 3475);
WIRE 74 -1 (-1925 3725)(-1625 3725);
WIRE 74 -1 (-1625 3850)(-1625 3725);
WIRE 74 -1 (-2225 3600)(-1925 3600);
WIRE 74 -1 (-1925 3725)(-1925 3600);
WIRE 74 -1 (-1925 3600)(-1625 3600);
WIRE 74 -1 (-1625 3725)(-1625 3600);
WIRE 74 -1 (-2225 3475)(-1925 3475);
WIRE 74 -1 (-1925 3600)(-1925 3475);
WIRE 74 -1 (-2500 3350)(-2225 3350);
WIRE 74 -1 (-2225 3475)(-2225 3350);
WIRE 74 -1 (-2800 3225)(-2500 3225);
WIRE 74 -1 (-2500 3350)(-2500 3225);
WIRE 74 -1 (-4550 3100)(-2800 3100);
WIRE 74 -1 (-2800 3225)(-2800 3100);
WIRE 74 -1 (-4550 2975)(-4550 3100);
WIRE 74 -1 (-2500 2475)(-2225 2475);
WIRE 74 -1 (-2800 2600)(-2500 2600);
WIRE 74 -1 (-2500 2600)(-2500 2475);
WIRE 74 -1 (-4550 2725)(-2800 2725);
WIRE 74 -1 (-2800 2725)(-2800 2600);
WIRE 74 -1 (-4550 2725)(-4550 2850);
WIRE 74 -1 (-4550 2850)(-4550 2975);
WIRE 74 -1 (-4550 2850)(-2800 2850);
WIRE 74 -1 (-2800 2850)(-2800 2725);
WIRE 74 -1 (-2800 2725)(-2500 2725);
WIRE 74 -1 (-2500 2725)(-2500 2600);
WIRE 74 -1 (-2225 2475)(-1925 2475);
WIRE 74 -1 (-2225 2600)(-2225 2475);
WIRE 74 -1 (-2500 2600)(-2225 2600);
WIRE 74 -1 (-4550 2975)(-2800 2975);
WIRE 74 -1 (-2800 3100)(-2800 2975);
WIRE 74 -1 (-2800 2975)(-2800 2850);
WIRE 74 -1 (-2800 3100)(-2500 3100);
WIRE 74 -1 (-2500 3225)(-2500 3100);
WIRE 74 -1 (-2500 3225)(-2225 3225);
WIRE 74 -1 (-2225 3350)(-2225 3225);
WIRE 74 -1 (-1925 3475)(-1625 3475);
WIRE 74 -1 (-1625 3600)(-1625 3475);
WIRE 74 -1 (-2225 3350)(-1925 3350);
WIRE 74 -1 (-1925 3475)(-1925 3350);
WIRE 74 -1 (-1925 3350)(-1625 3350);
WIRE 74 -1 (-1625 3475)(-1625 3350);
WIRE 74 -1 (-2225 3225)(-1925 3225);
WIRE 74 -1 (-1925 3350)(-1925 3225);
WIRE 74 -1 (-2500 3100)(-2225 3100);
WIRE 74 -1 (-2225 3225)(-2225 3100);
WIRE 74 -1 (-2800 2975)(-2500 2975);
WIRE 74 -1 (-2500 3100)(-2500 2975);
WIRE 74 -1 (-2225 2600)(-1925 2600);
WIRE 74 -1 (-1925 2600)(-1925 2475);
WIRE 74 -1 (-1925 2475)(-1625 2475);
WIRE 74 -1 (-2500 2725)(-2225 2725);
WIRE 74 -1 (-2225 2725)(-2225 2600);
WIRE 74 -1 (-2800 2850)(-2500 2850);
WIRE 74 -1 (-2500 2850)(-2500 2725);
WIRE 74 -1 (-2500 2975)(-2500 2850);
WIRE 74 -1 (-2500 2850)(-2225 2850);
WIRE 74 -1 (-2225 2850)(-2225 2725);
WIRE 74 -1 (-1625 2600)(-1625 2475);
WIRE 74 -1 (-1925 2600)(-1625 2600);
WIRE 74 -1 (-2225 2725)(-1925 2725);
WIRE 74 -1 (-1925 2725)(-1925 2600);
WIRE 74 -1 (-2500 2975)(-2225 2975);
WIRE 74 -1 (-2225 3100)(-2225 2975);
WIRE 74 -1 (-2225 2975)(-2225 2850);
WIRE 74 -1 (-1925 3225)(-1625 3225);
WIRE 74 -1 (-1625 3350)(-1625 3225);
WIRE 74 -1 (-2225 3100)(-1925 3100);
WIRE 74 -1 (-1925 3225)(-1925 3100);
WIRE 74 -1 (-1925 3100)(-1625 3100);
WIRE 74 -1 (-1625 3225)(-1625 3100);
WIRE 74 -1 (-2225 2975)(-1925 2975);
WIRE 74 -1 (-1925 3100)(-1925 2975);
WIRE 74 -1 (-1925 2725)(-1625 2725);
WIRE 74 -1 (-1625 2725)(-1625 2600);
WIRE 74 -1 (-2225 2850)(-1925 2850);
WIRE 74 -1 (-1925 2850)(-1925 2725);
WIRE 74 -1 (-1925 2975)(-1925 2850);
WIRE 74 -1 (-1925 2850)(-1625 2850);
WIRE 74 -1 (-1625 2850)(-1625 2725);
WIRE 74 -1 (-1925 2975)(-1625 2975);
WIRE 74 -1 (-1625 3100)(-1625 2975);
WIRE 74 -1 (-1625 2975)(-1625 2850);
WIRE 16 -1 (-25 2800)(-25 2325);
WIRE 16 -1 (-25 2325)(1050 2325);
FORCEPROP 2 LAST SIG_NAME FM_BOARD_BMC_SKU_ID0
J 0
(240 2335);
DISPLAY 0.808511 (240 2335);
PAINT WHITE (240 2335);
WIRE 16 -1 (-25 2175)(-25 2325);
WIRE 16 -1 (-125 5325)(-125 5475);
WIRE 16 -1 (-400 5325)(-400 5475);
WIRE 16 -1 (-400 5475)(-125 5475);
WIRE 16 -1 (-675 5325)(-675 5475);
WIRE 16 -1 (-675 5475)(-400 5475);
WIRE 16 -1 (-950 5475)(-675 5475);
WIRE 16 -1 (-950 5325)(-950 5475);
WIRE 16 -1 (-125 5125)(-125 4650);
WIRE 16 -1 (-125 4650)(950 4650);
FORCEPROP 2 LAST SIG_NAME FM_BOARD_SKU_ID0
J 0
(140 4660);
DISPLAY 0.808511 (140 4660);
PAINT WHITE (140 4660);
WIRE 16 -1 (-125 4500)(-125 4650);
WIRE 16 -1 (-400 5125)(-400 4725);
WIRE 16 -1 (-400 4725)(950 4725);
FORCEPROP 2 LAST SIG_NAME FM_BOARD_SKU_ID1
J 0
(140 4735);
DISPLAY 0.808511 (140 4735);
PAINT WHITE (140 4735);
WIRE 16 -1 (-400 4500)(-400 4725);
WIRE 16 -1 (-675 4800)(-675 5125);
WIRE 16 -1 (-675 4800)(950 4800);
FORCEPROP 2 LAST SIG_NAME FM_BOARD_SKU_ID2
J 0
(140 4810);
DISPLAY 0.808511 (140 4810);
PAINT WHITE (140 4810);
WIRE 16 -1 (-675 4500)(-675 4800);
WIRE 16 -1 (-575 2475)(-575 2800);
WIRE 16 -1 (-575 2475)(1050 2475);
FORCEPROP 2 LAST SIG_NAME FM_BOARD_BMC_SKU_ID2
J 0
(240 2485);
DISPLAY 0.808511 (240 2485);
PAINT WHITE (240 2485);
WIRE 16 -1 (-575 2175)(-575 2475);
WIRE 16 -1 (-300 2800)(-300 2400);
WIRE 16 -1 (-300 2400)(1050 2400);
FORCEPROP 2 LAST SIG_NAME FM_BOARD_BMC_SKU_ID1
J 0
(240 2410);
DISPLAY 0.808511 (240 2410);
PAINT WHITE (240 2410);
WIRE 16 -1 (-300 2175)(-300 2400);
WIRE 16 -1 (-1225 4950)(-1225 5125);
WIRE 16 -1 (950 4950)(-1225 4950);
FORCEPROP 2 LAST SIG_NAME FM_BOARD_SKU_ID4
J 0
(140 4960);
DISPLAY 0.808511 (140 4960);
PAINT WHITE (140 4960);
WIRE 16 -1 (-1225 4500)(-1225 4950);
WIRE 16 -1 (-950 4875)(-950 5125);
WIRE 16 -1 (-950 4875)(950 4875);
FORCEPROP 2 LAST SIG_NAME FM_BOARD_SKU_ID3
J 0
(140 4885);
DISPLAY 0.808511 (140 4885);
PAINT WHITE (140 4885);
WIRE 16 -1 (-950 4500)(-950 4875);
WIRE 16 -1 (-3450 4825)(-3450 4700);
WIRE 16 -1 (-3450 4825)(-3750 4825);
WIRE 16 -1 (-3750 4825)(-4550 4825);
WIRE 16 -1 (-3750 4825)(-3750 4700);
WIRE 16 -1 (-3750 4700)(-3450 4700);
WIRE 16 -1 (-3450 4700)(-3450 4575);
WIRE 16 -1 (-4550 4825)(-4550 4700);
WIRE 16 -1 (-4550 4700)(-3750 4700);
WIRE 16 -1 (-4550 4700)(-4550 4575);
WIRE 16 -1 (-3450 4575)(-3450 4450);
WIRE 16 -1 (-3750 4700)(-3750 4575);
WIRE 16 -1 (-3750 4575)(-3450 4575);
WIRE 16 -1 (-4550 4575)(-3750 4575);
WIRE 16 -1 (-3750 4575)(-3750 4450);
WIRE 16 -1 (-3750 4450)(-3450 4450);
WIRE 16 -1 (-4550 4450)(-4550 4575);
WIRE 16 -1 (-4550 4450)(-3750 4450);
WIRE 16 -1 (-850 2550)(-850 2800);
WIRE 16 -1 (-850 2550)(1050 2550);
FORCEPROP 2 LAST SIG_NAME FM_BOARD_BMC_SKU_ID3
J 0
(240 2560);
DISPLAY 0.808511 (240 2560);
PAINT WHITE (240 2560);
WIRE 16 -1 (-850 2175)(-850 2550);
WIRE 16 -1 (-1125 2625)(-1125 2800);
WIRE 16 -1 (1050 2625)(-1125 2625);
FORCEPROP 2 LAST SIG_NAME FM_BOARD_BMC_SKU_ID4
J 0
(240 2635);
DISPLAY 0.808511 (240 2635);
PAINT WHITE (240 2635);
WIRE 16 -1 (-1125 2175)(-1125 2625);
DOT 1 (2975 1025);
DOT 1 (2425 2250);
DOT 1 (3825 900);
DOT 1 (3825 650);
DOT 1 (3825 775);
DOT 1 (3825 525);
DOT 1 (3825 400);
DOT 1 (3400 900);
DOT 1 (3400 1025);
DOT 1 (3400 775);
DOT 1 (3400 650);
DOT 1 (3400 525);
DOT 1 (3400 400);
DOT 1 (2425 4725);
DOT 1 (2150 5400);
DOT 1 (1875 5400);
DOT 1 (2150 4800);
DOT 1 (1875 4875);
DOT 1 (2150 2925);
DOT 1 (1875 2925);
DOT 1 (1875 2400);
DOT 1 (2975 900);
DOT 1 (2975 775);
DOT 1 (2975 650);
DOT 1 (2975 525);
DOT 1 (2975 400);
DOT 1 (2575 1025);
DOT 1 (2575 900);
DOT 1 (2575 775);
DOT 1 (2575 650);
DOT 1 (2575 525);
DOT 1 (2575 400);
DOT 1 (2150 2325);
DOT 1 (2100 900);
DOT 1 (2100 775);
DOT 1 (2100 650);
DOT 1 (2100 525);
DOT 1 (2100 400);
DOT 1 (3825 150);
DOT 1 (3825 275);
DOT 1 (3825 25);
DOT 1 (3400 275);
DOT 1 (3400 150);
DOT 1 (3400 25);
DOT 1 (3400 -100);
DOT 1 (2975 275);
DOT 1 (2975 150);
DOT 1 (2975 -100);
DOT 1 (2975 25);
DOT 1 (2575 275);
DOT 1 (2575 150);
DOT 1 (2575 -100);
DOT 1 (2575 25);
DOT 1 (2100 275);
DOT 1 (2100 150);
DOT 1 (2100 25);
DOT 1 (-4550 2600);
DOT 1 (-4550 2725);
DOT 1 (-4550 2850);
DOT 1 (-4550 2975);
DOT 1 (-4550 3100);
DOT 1 (-4550 3225);
DOT 1 (-4550 3350);
DOT 1 (-4550 3475);
DOT 1 (-4550 3600);
DOT 1 (-4550 3850);
DOT 1 (-4550 3725);
DOT 1 (-4550 3975);
DOT 1 (-2800 2600);
DOT 1 (-2800 2475);
DOT 1 (-2800 2725);
DOT 1 (-2800 2850);
DOT 1 (-2800 2975);
DOT 1 (-2800 3100);
DOT 1 (-2800 3225);
DOT 1 (-2800 3350);
DOT 1 (-2800 3600);
DOT 1 (-2800 3475);
DOT 1 (-2800 3850);
DOT 1 (-2800 3725);
DOT 1 (-2800 4100);
DOT 1 (-2800 3975);
DOT 1 (-2500 2600);
DOT 1 (-2500 2475);
DOT 1 (-2500 2725);
DOT 1 (-2500 2850);
DOT 1 (-2500 2975);
DOT 1 (-2500 3100);
DOT 1 (-2500 3225);
DOT 1 (-2500 3350);
DOT 1 (-2225 2475);
DOT 1 (-2225 2600);
DOT 1 (-2225 2850);
DOT 1 (-2225 2725);
DOT 1 (-1925 2600);
DOT 1 (-1925 2475);
DOT 1 (-1925 2850);
DOT 1 (-1925 2725);
DOT 1 (-2225 2975);
DOT 1 (-2225 3100);
DOT 1 (-2225 3225);
DOT 1 (-2225 3350);
DOT 1 (-1925 2975);
DOT 1 (-1925 3100);
DOT 1 (-1925 3225);
DOT 1 (-1925 3350);
DOT 1 (-2500 3475);
DOT 1 (-2500 3600);
DOT 1 (-2500 3725);
DOT 1 (-2500 3850);
DOT 1 (-2500 3975);
DOT 1 (-2500 4100);
DOT 1 (-2225 3475);
DOT 1 (-2225 3600);
DOT 1 (-2225 3725);
DOT 1 (-2225 3850);
DOT 1 (-1925 3475);
DOT 1 (-1925 3600);
DOT 1 (-1925 3725);
DOT 1 (-1925 3850);
DOT 1 (-2225 4100);
DOT 1 (-2225 3975);
DOT 1 (-1925 3975);
DOT 1 (-1625 2600);
DOT 1 (-1625 2725);
DOT 1 (-1625 2850);
DOT 1 (-1625 3100);
DOT 1 (-1625 2975);
DOT 1 (-1625 3225);
DOT 1 (-1625 3350);
DOT 1 (-1125 2625);
DOT 1 (-850 2550);
DOT 1 (-1125 3150);
DOT 1 (-850 3150);
DOT 1 (-1625 3600);
DOT 1 (-1625 3475);
DOT 1 (-1625 3850);
DOT 1 (-1625 3975);
DOT 1 (-4550 4575);
DOT 1 (-4550 4700);
DOT 1 (-3750 4450);
DOT 1 (-3750 4575);
DOT 1 (-3750 4700);
DOT 1 (-3750 4825);
DOT 1 (-3450 4575);
DOT 1 (-3450 4700);
DOT 1 (-950 4875);
DOT 1 (-1225 4950);
DOT 1 (-1225 5475);
DOT 1 (-950 5475);
DOT 1 (-25 2325);
DOT 1 (-575 2475);
DOT 1 (-300 2400);
DOT 1 (-575 3150);
DOT 1 (-300 3150);
DOT 1 (-675 4800);
DOT 1 (-400 4725);
DOT 1 (-125 4650);
DOT 1 (-675 5475);
DOT 1 (-400 5475);
DOT 1 (-1925 4100);
DOT 1 (-1625 3725);
FORCENOTE
20220113 ADD ID PIN CONNECT TO FPGA
(1775 1550) 0;
DISPLAY LEFT (1775 1550);
DISPLAY 1.276596 (1775 1550);
PAINT PINK (1775 1550);
FORCENOTE
FAB_REV    ID2      ID1      ID0
(2175 925) 0;
DISPLAY LEFT (2175 925);
DISPLAY 1.021277 (2175 925);
PAINT WHITE (2175 925);
FORCENOTE
 POC        0        0        0
(2150 800) 0;
DISPLAY LEFT (2150 800);
DISPLAY 1.021277 (2150 800);
PAINT WHITE (2150 800);
FORCENOTE
 EVT        0        0        1
(2150 675) 0;
DISPLAY LEFT (2150 675);
DISPLAY 1.021277 (2150 675);
PAINT WHITE (2150 675);
FORCENOTE
 EVT2       0        1        0
(2150 550) 0;
DISPLAY LEFT (2150 550);
DISPLAY 1.021277 (2150 550);
PAINT WHITE (2150 550);
FORCENOTE
 DVT        0        1        1
(2150 425) 0;
DISPLAY LEFT (2150 425);
DISPLAY 1.021277 (2150 425);
PAINT WHITE (2150 425);
FORCENOTE
 DVT2       1        0        0
(2150 300) 0;
DISPLAY LEFT (2150 300);
DISPLAY 1.021277 (2150 300);
PAINT WHITE (2150 300);
FORCENOTE
 PVT        1        0        1
(2150 200) 0;
DISPLAY LEFT (2150 200);
DISPLAY 1.021277 (2150 200);
PAINT WHITE (2150 200);
FORCENOTE
 PILOT      1        1        0
(2150 75) 0;
DISPLAY LEFT (2150 75);
DISPLAY 1.021277 (2150 75);
PAINT GREEN (2150 75);
FORCENOTE
 MP         1        1        1
(2150 -50) 0;
DISPLAY LEFT (2150 -50);
DISPLAY 1.021277 (2150 -50);
PAINT GREEN (2150 -50);
FORCENOTE
HSC-MPS5990 + ADC-MAM + VR-TIC
(-4475 3525) 0;
DISPLAY LEFT (-4475 3525);
DISPLAY 1.021277 (-4475 3525);
PAINT WHITE (-4475 3525);
FORCENOTE
HSC-MPS5990 + ADC-MAM + VR-MPS
(-4475 3650) 0;
DISPLAY LEFT (-4475 3650);
DISPLAY 1.021277 (-4475 3650);
PAINT WHITE (-4475 3650);
FORCENOTE
HSC-MPS5990 + ADC-TIC + VR-SNI
(-4475 3775) 0;
DISPLAY LEFT (-4475 3775);
DISPLAY 1.021277 (-4475 3775);
PAINT WHITE (-4475 3775);
FORCENOTE
HSC-MPS5990 + ADC-TIC + VR-RTT
(-4475 3900) 0;
DISPLAY LEFT (-4475 3900);
DISPLAY 1.021277 (-4475 3900);
PAINT GREEN (-4475 3900);
FORCENOTE
 1
(-1825 3250) 0;
DISPLAY LEFT (-1825 3250);
DISPLAY 1.021277 (-1825 3250);
PAINT WHITE (-1825 3250);
FORCENOTE
 0
(-2125 3250) 0;
DISPLAY LEFT (-2125 3250);
DISPLAY 1.021277 (-2125 3250);
PAINT WHITE (-2125 3250);
FORCENOTE
 1
(-2425 3250) 0;
DISPLAY LEFT (-2425 3250);
DISPLAY 1.021277 (-2425 3250);
PAINT WHITE (-2425 3250);
FORCENOTE
HSC-MODULE + ADC-TIC + VR-RTT
(-4475 3400) 0;
DISPLAY LEFT (-4475 3400);
DISPLAY 1.021277 (-4475 3400);
PAINT WHITE (-4475 3400);
FORCENOTE
20211208 MODIFY FOR GT
(-5050 5825) 0;
DISPLAY LEFT (-5050 5825);
DISPLAY 2.510638 (-5050 5825);
PAINT PINK (-5050 5825);
FORCENOTE
HSC-REEDSEMI + ADC-TIC + VR-RTT
(-4475 2900) 0;
DISPLAY LEFT (-4475 2900);
DISPLAY 1.021277 (-4475 2900);
PAINT WHITE (-4475 2900);
FORCENOTE
HSC-REEDSEMI + ADC-TIC + VR-SNI
(-4475 2775) 0;
DISPLAY LEFT (-4475 2775);
DISPLAY 1.021277 (-4475 2775);
PAINT WHITE (-4475 2775);
FORCENOTE
HSC-REEDSEMI + ADC-MAM + VR-TIC
(-4475 2525) 0;
DISPLAY LEFT (-4475 2525);
DISPLAY 1.021277 (-4475 2525);
PAINT WHITE (-4475 2525);
FORCENOTE
HSC-REEDSEMI + ADC-MAM + VR-MPS
(-4475 2650) 0;
DISPLAY LEFT (-4475 2650);
DISPLAY 1.021277 (-4475 2650);
PAINT WHITE (-4475 2650);
FORCENOTE
HSC-MODULE + ADC-MAM + VR-TIC
(-4475 3025) 0;
DISPLAY LEFT (-4475 3025);
DISPLAY 1.021277 (-4475 3025);
PAINT WHITE (-4475 3025);
FORCENOTE
HSC-MODULE + ADC-MAM + VR-MPS
(-4475 3150) 0;
DISPLAY LEFT (-4475 3150);
DISPLAY 1.021277 (-4475 3150);
PAINT WHITE (-4475 3150);
FORCENOTE
HSC-MODULE + ADC-TIC + VR-SNI
(-4475 3275) 0;
DISPLAY LEFT (-4475 3275);
DISPLAY 1.021277 (-4475 3275);
PAINT WHITE (-4475 3275);
FORCENOTE
BRD_SKU
(-3825 4025) 0;
DISPLAY LEFT (-3825 4025);
DISPLAY 1.021277 (-3825 4025);
PAINT WHITE (-3825 4025);
FORCENOTE
 1
(-2700 2750) 0;
DISPLAY LEFT (-2700 2750);
DISPLAY 1.021277 (-2700 2750);
PAINT WHITE (-2700 2750);
FORCENOTE
 1
(-2700 2625) 0;
DISPLAY LEFT (-2700 2625);
DISPLAY 1.021277 (-2700 2625);
PAINT WHITE (-2700 2625);
FORCENOTE
 1
(-2700 2500) 0;
DISPLAY LEFT (-2700 2500);
DISPLAY 1.021277 (-2700 2500);
PAINT WHITE (-2700 2500);
FORCENOTE
 0
(-2425 2500) 0;
DISPLAY LEFT (-2425 2500);
DISPLAY 1.021277 (-2425 2500);
PAINT WHITE (-2425 2500);
FORCENOTE
 0
(-2425 2625) 0;
DISPLAY LEFT (-2425 2625);
DISPLAY 1.021277 (-2425 2625);
PAINT WHITE (-2425 2625);
FORCENOTE
 0
(-2425 2750) 0;
DISPLAY LEFT (-2425 2750);
DISPLAY 1.021277 (-2425 2750);
PAINT WHITE (-2425 2750);
FORCENOTE
 0
(-2700 3250) 0;
DISPLAY LEFT (-2700 3250);
DISPLAY 1.021277 (-2700 3250);
PAINT WHITE (-2700 3250);
FORCENOTE
 0
(-2700 3125) 0;
DISPLAY LEFT (-2700 3125);
DISPLAY 1.021277 (-2700 3125);
PAINT WHITE (-2700 3125);
FORCENOTE
 1
(-2700 2875) 0;
DISPLAY LEFT (-2700 2875);
DISPLAY 1.021277 (-2700 2875);
PAINT WHITE (-2700 2875);
FORCENOTE
 0
(-2700 3000) 0;
DISPLAY LEFT (-2700 3000);
DISPLAY 1.021277 (-2700 3000);
PAINT WHITE (-2700 3000);
FORCENOTE
 0
(-2425 2875) 0;
DISPLAY LEFT (-2425 2875);
DISPLAY 1.021277 (-2425 2875);
PAINT WHITE (-2425 2875);
FORCENOTE
 1
(-2425 3000) 0;
DISPLAY LEFT (-2425 3000);
DISPLAY 1.021277 (-2425 3000);
PAINT WHITE (-2425 3000);
FORCENOTE
 1
(-2425 3125) 0;
DISPLAY LEFT (-2425 3125);
DISPLAY 1.021277 (-2425 3125);
PAINT WHITE (-2425 3125);
FORCENOTE
 1
(-2125 2625) 0;
DISPLAY LEFT (-2125 2625);
DISPLAY 1.021277 (-2125 2625);
PAINT WHITE (-2125 2625);
FORCENOTE
 1
(-2125 2500) 0;
DISPLAY LEFT (-2125 2500);
DISPLAY 1.021277 (-2125 2500);
PAINT WHITE (-2125 2500);
FORCENOTE
 0
(-2125 2750) 0;
DISPLAY LEFT (-2125 2750);
DISPLAY 1.021277 (-2125 2750);
PAINT WHITE (-2125 2750);
FORCENOTE
 1
(-2125 3125) 0;
DISPLAY LEFT (-2125 3125);
DISPLAY 1.021277 (-2125 3125);
PAINT WHITE (-2125 3125);
FORCENOTE
 1
(-2125 3000) 0;
DISPLAY LEFT (-2125 3000);
DISPLAY 1.021277 (-2125 3000);
PAINT WHITE (-2125 3000);
FORCENOTE
 0
(-2125 2875) 0;
DISPLAY LEFT (-2125 2875);
DISPLAY 1.021277 (-2125 2875);
PAINT WHITE (-2125 2875);
FORCENOTE
 0
(-2700 3500) 0;
DISPLAY LEFT (-2700 3500);
DISPLAY 1.021277 (-2700 3500);
PAINT WHITE (-2700 3500);
FORCENOTE
 0
(-2700 3750) 0;
DISPLAY LEFT (-2700 3750);
DISPLAY 1.021277 (-2700 3750);
PAINT WHITE (-2700 3750);
FORCENOTE
 0
(-2700 3625) 0;
DISPLAY LEFT (-2700 3625);
DISPLAY 1.021277 (-2700 3625);
PAINT WHITE (-2700 3625);
FORCENOTE
 0
(-2700 3375) 0;
DISPLAY LEFT (-2700 3375);
DISPLAY 1.021277 (-2700 3375);
PAINT WHITE (-2700 3375);
FORCENOTE
 1
(-2425 3375) 0;
DISPLAY LEFT (-2425 3375);
DISPLAY 1.021277 (-2425 3375);
PAINT WHITE (-2425 3375);
FORCENOTE
 0
(-2425 3500) 0;
DISPLAY LEFT (-2425 3500);
DISPLAY 1.021277 (-2425 3500);
PAINT WHITE (-2425 3500);
FORCENOTE
 0
(-2425 3625) 0;
DISPLAY LEFT (-2425 3625);
DISPLAY 1.021277 (-2425 3625);
PAINT WHITE (-2425 3625);
FORCENOTE
 0
(-2425 3750) 0;
DISPLAY LEFT (-2425 3750);
DISPLAY 1.021277 (-2425 3750);
PAINT WHITE (-2425 3750);
FORCENOTE
 0
(-2425 3875) 0;
DISPLAY LEFT (-2425 3875);
DISPLAY 1.021277 (-2425 3875);
PAINT GREEN (-2425 3875);
FORCENOTE
 0
(-2700 3875) 0;
DISPLAY LEFT (-2700 3875);
DISPLAY 1.021277 (-2700 3875);
PAINT GREEN (-2700 3875);
FORCENOTE
ID3
(-2725 4000) 0;
DISPLAY LEFT (-2725 4000);
DISPLAY 1.021277 (-2725 4000);
PAINT WHITE (-2725 4000);
FORCENOTE
ID2
(-2450 4000) 0;
DISPLAY LEFT (-2450 4000);
DISPLAY 1.021277 (-2450 4000);
PAINT WHITE (-2450 4000);
FORCENOTE
 1
(-2125 3500) 0;
DISPLAY LEFT (-2125 3500);
DISPLAY 1.021277 (-2125 3500);
PAINT WHITE (-2125 3500);
FORCENOTE
 1
(-2125 3625) 0;
DISPLAY LEFT (-2125 3625);
DISPLAY 1.021277 (-2125 3625);
PAINT WHITE (-2125 3625);
FORCENOTE
 0
(-2125 3750) 0;
DISPLAY LEFT (-2125 3750);
DISPLAY 1.021277 (-2125 3750);
PAINT WHITE (-2125 3750);
FORCENOTE
 0
(-2125 3375) 0;
DISPLAY LEFT (-2125 3375);
DISPLAY 1.021277 (-2125 3375);
PAINT WHITE (-2125 3375);
FORCENOTE
 0
(-2125 3875) 0;
DISPLAY LEFT (-2125 3875);
DISPLAY 1.021277 (-2125 3875);
PAINT GREEN (-2125 3875);
FORCENOTE
 1
(-1825 2750) 0;
DISPLAY LEFT (-1825 2750);
DISPLAY 1.021277 (-1825 2750);
PAINT WHITE (-1825 2750);
FORCENOTE
 1
(-1825 3500) 0;
DISPLAY LEFT (-1825 3500);
DISPLAY 1.021277 (-1825 3500);
PAINT WHITE (-1825 3500);
FORCENOTE
 0
(-1825 3125) 0;
DISPLAY LEFT (-1825 3125);
DISPLAY 1.021277 (-1825 3125);
PAINT WHITE (-1825 3125);
FORCENOTE
 0
(-1825 2875) 0;
DISPLAY LEFT (-1825 2875);
DISPLAY 1.021277 (-1825 2875);
PAINT WHITE (-1825 2875);
FORCENOTE
 0
(-1825 2625) 0;
DISPLAY LEFT (-1825 2625);
DISPLAY 1.021277 (-1825 2625);
PAINT WHITE (-1825 2625);
FORCENOTE
 1
(-1825 2500) 0;
DISPLAY LEFT (-1825 2500);
DISPLAY 1.021277 (-1825 2500);
PAINT WHITE (-1825 2500);
FORCENOTE
 0
(-1825 3375) 0;
DISPLAY LEFT (-1825 3375);
DISPLAY 1.021277 (-1825 3375);
PAINT WHITE (-1825 3375);
FORCENOTE
 1
(-1825 3000) 0;
DISPLAY LEFT (-1825 3000);
DISPLAY 1.021277 (-1825 3000);
PAINT WHITE (-1825 3000);
FORCENOTE
 0
(-1825 3625) 0;
DISPLAY LEFT (-1825 3625);
DISPLAY 1.021277 (-1825 3625);
PAINT WHITE (-1825 3625);
FORCENOTE
AMD PLATFORM
(-4475 4500) 0;
DISPLAY LEFT (-4475 4500);
DISPLAY 1.021277 (-4475 4500);
PAINT WHITE (-4475 4500);
FORCENOTE
BRD_SKU
(-4325 4725) 0;
DISPLAY LEFT (-4325 4725);
DISPLAY 1.021277 (-4325 4725);
PAINT WHITE (-4325 4725);
FORCENOTE
INTEL PLATFORM
(-4475 4625) 0;
DISPLAY LEFT (-4475 4625);
DISPLAY 1.021277 (-4475 4625);
PAINT GREEN (-4475 4625);
FORCENOTE
 1
(-3650 4475) 0;
DISPLAY LEFT (-3650 4475);
DISPLAY 1.021277 (-3650 4475);
PAINT WHITE (-3650 4475);
FORCENOTE
ID4
(-3675 4725) 0;
DISPLAY LEFT (-3675 4725);
DISPLAY 1.021277 (-3675 4725);
PAINT WHITE (-3675 4725);
FORCENOTE
 0
(-3650 4600) 0;
DISPLAY LEFT (-3650 4600);
DISPLAY 1.021277 (-3650 4600);
PAINT GREEN (-3650 4600);
FORCENOTE
20220113 ADD ID PIN CONNECT TO FPGA
(-675 1575) 0;
DISPLAY LEFT (-675 1575);
DISPLAY 1.276596 (-675 1575);
PAINT PINK (-675 1575);
FORCENOTE
 1
(-1825 3750) 0;
DISPLAY LEFT (-1825 3750);
DISPLAY 1.021277 (-1825 3750);
PAINT WHITE (-1825 3750);
FORCENOTE
 0
(-1825 3875) 0;
DISPLAY LEFT (-1825 3875);
DISPLAY 1.021277 (-1825 3875);
PAINT GREEN (-1825 3875);
FORCENOTE
ID0
(-1875 4000) 0;
DISPLAY LEFT (-1875 4000);
DISPLAY 1.021277 (-1875 4000);
PAINT WHITE (-1875 4000);
FORCENOTE
ID1
(-2150 4000) 0;
DISPLAY LEFT (-2150 4000);
DISPLAY 1.021277 (-2150 4000);
PAINT WHITE (-2150 4000);
QUIT
